(kicad_sch
	(version 20250114)
	(generator "eeschema")
	(generator_version "9.0")
	(paper "A3")
	(title_block
		(title "COM Express 7 Baseboard")
		(date "2025-02-04")
		(rev "1.1.2")
		(company "Antmicro Ltd")
		(comment 1 "www.antmicro.com")
	)
	(text "LED polarity missing from \ndatasheet so we're ready for both"
		(exclude_from_sim no)
		(at 77.47 100.33 0)
		(effects
			(font
				(size 1.27 1.27)
			)
			(justify left bottom)
		)
	)
	(text "GbE RJ45"
		(exclude_from_sim no)
		(at 213.36 22.86 0)
		(effects
			(font
				(size 2 2)
				(thickness 0.4)
				(bold yes)
			)
			(justify left bottom)
		)
	)
	(text "USB 3.0"
		(exclude_from_sim no)
		(at 213.36 129.54 0)
		(effects
			(font
				(size 2 2)
				(thickness 0.4)
				(bold yes)
			)
			(justify left bottom)
		)
	)
	(junction
		(at 128.27 63.5)
		(diameter 0)
		(color 0 0 0 0)
	)
	(junction
		(at 195.58 224.79)
		(diameter 0)
		(color 0 0 0 0)
	)
	(junction
		(at 110.49 74.93)
		(diameter 0)
		(color 0 0 0 0)
	)
	(junction
		(at 86.36 86.36)
		(diameter 0)
		(color 0 0 0 0)
	)
	(junction
		(at 163.83 92.71)
		(diameter 0)
		(color 0 0 0 0)
	)
	(junction
		(at 182.88 154.94)
		(diameter 0)
		(color 0 0 0 0)
	)
	(junction
		(at 180.34 181.61)
		(diameter 0)
		(color 0 0 0 0)
	)
	(junction
		(at 227.33 243.84)
		(diameter 0)
		(color 0 0 0 0)
	)
	(junction
		(at 133.35 74.93)
		(diameter 0)
		(color 0 0 0 0)
	)
	(junction
		(at 106.68 83.82)
		(diameter 0)
		(color 0 0 0 0)
	)
	(junction
		(at 232.41 93.98)
		(diameter 0)
		(color 0 0 0 0)
	)
	(junction
		(at 149.86 224.79)
		(diameter 0)
		(color 0 0 0 0)
	)
	(junction
		(at 261.62 68.58)
		(diameter 0)
		(color 0 0 0 0)
	)
	(junction
		(at 118.11 86.36)
		(diameter 0)
		(color 0 0 0 0)
	)
	(junction
		(at 163.83 106.68)
		(diameter 0)
		(color 0 0 0 0)
	)
	(junction
		(at 270.51 212.09)
		(diameter 0)
		(color 0 0 0 0)
	)
	(junction
		(at 241.3 149.86)
		(diameter 0)
		(color 0 0 0 0)
	)
	(junction
		(at 177.8 254)
		(diameter 0)
		(color 0 0 0 0)
	)
	(junction
		(at 149.86 154.94)
		(diameter 0)
		(color 0 0 0 0)
	)
	(junction
		(at 233.68 157.48)
		(diameter 0)
		(color 0 0 0 0)
	)
	(junction
		(at 172.72 248.92)
		(diameter 0)
		(color 0 0 0 0)
	)
	(junction
		(at 232.41 68.58)
		(diameter 0)
		(color 0 0 0 0)
	)
	(junction
		(at 229.87 171.45)
		(diameter 0)
		(color 0 0 0 0)
	)
	(junction
		(at 182.88 224.79)
		(diameter 0)
		(color 0 0 0 0)
	)
	(junction
		(at 134.62 66.04)
		(diameter 0)
		(color 0 0 0 0)
	)
	(junction
		(at 270.51 142.24)
		(diameter 0)
		(color 0 0 0 0)
	)
	(junction
		(at 280.67 142.24)
		(diameter 0)
		(color 0 0 0 0)
	)
	(junction
		(at 137.16 259.08)
		(diameter 0)
		(color 0 0 0 0)
	)
	(junction
		(at 180.34 251.46)
		(diameter 0)
		(color 0 0 0 0)
	)
	(junction
		(at 175.26 176.53)
		(diameter 0)
		(color 0 0 0 0)
	)
	(junction
		(at 133.35 63.5)
		(diameter 0)
		(color 0 0 0 0)
	)
	(junction
		(at 261.62 55.88)
		(diameter 0)
		(color 0 0 0 0)
	)
	(junction
		(at 90.17 63.5)
		(diameter 0)
		(color 0 0 0 0)
	)
	(junction
		(at 280.67 212.09)
		(diameter 0)
		(color 0 0 0 0)
	)
	(junction
		(at 160.02 224.79)
		(diameter 0)
		(color 0 0 0 0)
	)
	(junction
		(at 227.33 173.99)
		(diameter 0)
		(color 0 0 0 0)
	)
	(junction
		(at 261.62 81.28)
		(diameter 0)
		(color 0 0 0 0)
	)
	(junction
		(at 172.72 179.07)
		(diameter 0)
		(color 0 0 0 0)
	)
	(junction
		(at 109.22 86.36)
		(diameter 0)
		(color 0 0 0 0)
	)
	(junction
		(at 261.62 93.98)
		(diameter 0)
		(color 0 0 0 0)
	)
	(junction
		(at 233.68 227.33)
		(diameter 0)
		(color 0 0 0 0)
	)
	(junction
		(at 204.47 233.68)
		(diameter 0)
		(color 0 0 0 0)
	)
	(junction
		(at 232.41 81.28)
		(diameter 0)
		(color 0 0 0 0)
	)
	(junction
		(at 134.62 52.07)
		(diameter 0)
		(color 0 0 0 0)
	)
	(junction
		(at 128.27 66.04)
		(diameter 0)
		(color 0 0 0 0)
	)
	(junction
		(at 204.47 163.83)
		(diameter 0)
		(color 0 0 0 0)
	)
	(junction
		(at 110.49 83.82)
		(diameter 0)
		(color 0 0 0 0)
	)
	(junction
		(at 241.3 219.71)
		(diameter 0)
		(color 0 0 0 0)
	)
	(junction
		(at 88.9 83.82)
		(diameter 0)
		(color 0 0 0 0)
	)
	(junction
		(at 229.87 241.3)
		(diameter 0)
		(color 0 0 0 0)
	)
	(junction
		(at 195.58 154.94)
		(diameter 0)
		(color 0 0 0 0)
	)
	(junction
		(at 175.26 246.38)
		(diameter 0)
		(color 0 0 0 0)
	)
	(junction
		(at 241.3 160.02)
		(diameter 0)
		(color 0 0 0 0)
	)
	(junction
		(at 177.8 184.15)
		(diameter 0)
		(color 0 0 0 0)
	)
	(junction
		(at 160.02 154.94)
		(diameter 0)
		(color 0 0 0 0)
	)
	(junction
		(at 241.3 229.87)
		(diameter 0)
		(color 0 0 0 0)
	)
	(junction
		(at 137.16 189.23)
		(diameter 0)
		(color 0 0 0 0)
	)
	(bus_entry
		(at 293.37 93.98)
		(size -1.27 1.27)
		(stroke
			(width 0)
			(type default)
		)
	)
	(bus_entry
		(at 293.37 91.44)
		(size -1.27 1.27)
		(stroke
			(width 0)
			(type default)
		)
	)
	(bus_entry
		(at 222.25 182.88)
		(size -1.27 -1.27)
		(stroke
			(width 0)
			(type default)
		)
	)
	(bus_entry
		(at 293.37 48.26)
		(size -1.27 1.27)
		(stroke
			(width 0)
			(type default)
		)
	)
	(bus_entry
		(at 259.08 170.18)
		(size -1.27 1.27)
		(stroke
			(width 0)
			(type default)
		)
	)
	(bus_entry
		(at 293.37 81.28)
		(size -1.27 1.27)
		(stroke
			(width 0)
			(type default)
		)
	)
	(bus_entry
		(at 222.25 252.73)
		(size -1.27 -1.27)
		(stroke
			(width 0)
			(type default)
		)
	)
	(bus_entry
		(at 259.08 240.03)
		(size -1.27 1.27)
		(stroke
			(width 0)
			(type default)
		)
	)
	(bus_entry
		(at 293.37 55.88)
		(size -1.27 1.27)
		(stroke
			(width 0)
			(type default)
		)
	)
	(bus_entry
		(at 293.37 53.34)
		(size -1.27 1.27)
		(stroke
			(width 0)
			(type default)
		)
	)
	(bus_entry
		(at 222.25 250.19)
		(size -1.27 -1.27)
		(stroke
			(width 0)
			(type default)
		)
	)
	(bus_entry
		(at 222.25 255.27)
		(size -1.27 -1.27)
		(stroke
			(width 0)
			(type default)
		)
	)
	(bus_entry
		(at 222.25 247.65)
		(size -1.27 -1.27)
		(stroke
			(width 0)
			(type default)
		)
	)
	(bus_entry
		(at 222.25 177.8)
		(size -1.27 -1.27)
		(stroke
			(width 0)
			(type default)
		)
	)
	(bus_entry
		(at 259.08 172.72)
		(size -1.27 1.27)
		(stroke
			(width 0)
			(type default)
		)
	)
	(bus_entry
		(at 259.08 242.57)
		(size -1.27 1.27)
		(stroke
			(width 0)
			(type default)
		)
	)
	(bus_entry
		(at 222.25 180.34)
		(size -1.27 -1.27)
		(stroke
			(width 0)
			(type default)
		)
	)
	(bus_entry
		(at 222.25 185.42)
		(size -1.27 -1.27)
		(stroke
			(width 0)
			(type default)
		)
	)
	(bus_entry
		(at 293.37 66.04)
		(size -1.27 1.27)
		(stroke
			(width 0)
			(type default)
		)
	)
	(bus_entry
		(at 293.37 68.58)
		(size -1.27 1.27)
		(stroke
			(width 0)
			(type default)
		)
	)
	(bus_entry
		(at 293.37 78.74)
		(size -1.27 1.27)
		(stroke
			(width 0)
			(type default)
		)
	)
	(wire
		(pts
			(xy 208.28 160.02) (xy 207.01 160.02)
		)
		(stroke
			(width 0)
			(type default)
		)
	)
	(wire
		(pts
			(xy 241.3 220.98) (xy 241.3 219.71)
		)
		(stroke
			(width 0)
			(type default)
		)
	)
	(wire
		(pts
			(xy 248.92 160.02) (xy 241.3 160.02)
		)
		(stroke
			(width 0)
			(type default)
		)
	)
	(wire
		(pts
			(xy 220.98 58.42) (xy 245.11 58.42)
		)
		(stroke
			(width 0)
			(type default)
		)
	)
	(wire
		(pts
			(xy 255.27 96.52) (xy 262.89 96.52)
		)
		(stroke
			(width 0)
			(type default)
		)
	)
	(wire
		(pts
			(xy 280.67 142.24) (xy 270.51 142.24)
		)
		(stroke
			(width 0)
			(type default)
		)
	)
	(wire
		(pts
			(xy 220.98 83.82) (xy 245.11 83.82)
		)
		(stroke
			(width 0)
			(type default)
		)
	)
	(wire
		(pts
			(xy 232.41 93.98) (xy 237.49 93.98)
		)
		(stroke
			(width 0)
			(type default)
		)
	)
	(wire
		(pts
			(xy 257.81 243.84) (xy 238.76 243.84)
		)
		(stroke
			(width 0)
			(type default)
		)
	)
	(wire
		(pts
			(xy 149.86 154.94) (xy 149.86 157.48)
		)
		(stroke
			(width 0)
			(type default)
		)
	)
	(wire
		(pts
			(xy 128.27 54.61) (xy 128.27 52.07)
		)
		(stroke
			(width 0)
			(type default)
		)
	)
	(bus
		(pts
			(xy 222.25 252.73) (xy 222.25 250.19)
		)
		(stroke
			(width 0)
			(type default)
		)
	)
	(bus
		(pts
			(xy 222.25 182.88) (xy 222.25 185.42)
		)
		(stroke
			(width 0)
			(type default)
		)
	)
	(wire
		(pts
			(xy 241.3 156.21) (xy 241.3 160.02)
		)
		(stroke
			(width 0)
			(type default)
		)
	)
	(wire
		(pts
			(xy 257.81 173.99) (xy 238.76 173.99)
		)
		(stroke
			(width 0)
			(type default)
		)
	)
	(wire
		(pts
			(xy 180.34 181.61) (xy 180.34 190.5)
		)
		(stroke
			(width 0)
			(type default)
		)
	)
	(wire
		(pts
			(xy 262.89 95.25) (xy 292.1 95.25)
		)
		(stroke
			(width 0)
			(type default)
		)
	)
	(wire
		(pts
			(xy 182.88 189.23) (xy 182.88 190.5)
		)
		(stroke
			(width 0)
			(type default)
		)
	)
	(wire
		(pts
			(xy 257.81 241.3) (xy 238.76 241.3)
		)
		(stroke
			(width 0)
			(type default)
		)
	)
	(wire
		(pts
			(xy 182.88 224.79) (xy 182.88 227.33)
		)
		(stroke
			(width 0)
			(type default)
		)
	)
	(wire
		(pts
			(xy 133.35 76.2) (xy 133.35 74.93)
		)
		(stroke
			(width 0)
			(type default)
		)
	)
	(wire
		(pts
			(xy 262.89 83.82) (xy 262.89 82.55)
		)
		(stroke
			(width 0)
			(type default)
		)
	)
	(wire
		(pts
			(xy 99.06 86.36) (xy 109.22 86.36)
		)
		(stroke
			(width 0)
			(type default)
		)
	)
	(wire
		(pts
			(xy 184.15 57.15) (xy 200.66 57.15)
		)
		(stroke
			(width 0)
			(type default)
		)
	)
	(wire
		(pts
			(xy 228.6 212.09) (xy 228.6 224.79)
		)
		(stroke
			(width 0)
			(type default)
		)
	)
	(wire
		(pts
			(xy 106.68 83.82) (xy 106.68 90.17)
		)
		(stroke
			(width 0)
			(type default)
		)
	)
	(wire
		(pts
			(xy 163.83 86.36) (xy 162.56 86.36)
		)
		(stroke
			(width 0)
			(type default)
		)
	)
	(wire
		(pts
			(xy 262.89 58.42) (xy 262.89 57.15)
		)
		(stroke
			(width 0)
			(type default)
		)
	)
	(wire
		(pts
			(xy 88.9 90.17) (xy 88.9 83.82)
		)
		(stroke
			(width 0)
			(type default)
		)
	)
	(wire
		(pts
			(xy 128.27 73.66) (xy 128.27 74.93)
		)
		(stroke
			(width 0)
			(type default)
		)
	)
	(wire
		(pts
			(xy 210.82 66.04) (xy 200.66 66.04)
		)
		(stroke
			(width 0)
			(type default)
		)
	)
	(wire
		(pts
			(xy 220.98 96.52) (xy 245.11 96.52)
		)
		(stroke
			(width 0)
			(type default)
		)
	)
	(wire
		(pts
			(xy 162.56 73.66) (xy 190.5 73.66)
		)
		(stroke
			(width 0)
			(type default)
		)
	)
	(wire
		(pts
			(xy 198.12 69.85) (xy 200.66 69.85)
		)
		(stroke
			(width 0)
			(type default)
		)
	)
	(bus
		(pts
			(xy 260.35 238.76) (xy 259.08 240.03)
		)
		(stroke
			(width 0)
			(type default)
		)
	)
	(wire
		(pts
			(xy 135.89 246.38) (xy 175.26 246.38)
		)
		(stroke
			(width 0)
			(type default)
		)
	)
	(wire
		(pts
			(xy 232.41 175.26) (xy 237.49 175.26)
		)
		(stroke
			(width 0)
			(type default)
		)
	)
	(wire
		(pts
			(xy 232.41 176.53) (xy 232.41 175.26)
		)
		(stroke
			(width 0)
			(type default)
		)
	)
	(wire
		(pts
			(xy 200.66 66.04) (xy 200.66 67.31)
		)
		(stroke
			(width 0)
			(type default)
		)
	)
	(wire
		(pts
			(xy 195.58 233.68) (xy 195.58 232.41)
		)
		(stroke
			(width 0)
			(type default)
		)
	)
	(wire
		(pts
			(xy 135.89 251.46) (xy 180.34 251.46)
		)
		(stroke
			(width 0)
			(type default)
		)
	)
	(bus
		(pts
			(xy 222.25 182.88) (xy 222.25 180.34)
		)
		(stroke
			(width 0)
			(type default)
		)
	)
	(wire
		(pts
			(xy 200.66 91.44) (xy 200.66 92.71)
		)
		(stroke
			(width 0)
			(type default)
		)
	)
	(bus
		(pts
			(xy 269.24 187.96) (xy 223.52 187.96)
		)
		(stroke
			(width 0)
			(type default)
		)
	)
	(wire
		(pts
			(xy 241.3 218.44) (xy 241.3 219.71)
		)
		(stroke
			(width 0)
			(type default)
		)
	)
	(wire
		(pts
			(xy 229.87 171.45) (xy 135.89 171.45)
		)
		(stroke
			(width 0)
			(type default)
		)
	)
	(bus
		(pts
			(xy 222.25 186.69) (xy 222.25 185.42)
		)
		(stroke
			(width 0)
			(type default)
		)
	)
	(wire
		(pts
			(xy 267.97 100.33) (xy 267.97 81.28)
		)
		(stroke
			(width 0)
			(type default)
		)
	)
	(wire
		(pts
			(xy 280.67 105.41) (xy 280.67 106.68)
		)
		(stroke
			(width 0)
			(type default)
		)
	)
	(wire
		(pts
			(xy 227.33 173.99) (xy 227.33 176.53)
		)
		(stroke
			(width 0)
			(type default)
		)
	)
	(wire
		(pts
			(xy 162.56 71.12) (xy 193.04 71.12)
		)
		(stroke
			(width 0)
			(type default)
		)
	)
	(wire
		(pts
			(xy 208.28 227.33) (xy 204.47 227.33)
		)
		(stroke
			(width 0)
			(type default)
		)
	)
	(wire
		(pts
			(xy 172.72 248.92) (xy 220.98 248.92)
		)
		(stroke
			(width 0)
			(type default)
		)
	)
	(wire
		(pts
			(xy 187.96 260.35) (xy 187.96 259.08)
		)
		(stroke
			(width 0)
			(type default)
		)
	)
	(wire
		(pts
			(xy 228.6 142.24) (xy 228.6 154.94)
		)
		(stroke
			(width 0)
			(type default)
		)
	)
	(wire
		(pts
			(xy 227.33 243.84) (xy 227.33 247.65)
		)
		(stroke
			(width 0)
			(type default)
		)
	)
	(wire
		(pts
			(xy 262.89 54.61) (xy 292.1 54.61)
		)
		(stroke
			(width 0)
			(type default)
		)
	)
	(bus
		(pts
			(xy 293.37 55.88) (xy 293.37 66.04)
		)
		(stroke
			(width 0)
			(type default)
		)
	)
	(polyline
		(pts
			(xy 12.7 121.92) (xy 406.4 121.92)
		)
		(stroke
			(width 0)
			(type dash)
		)
	)
	(wire
		(pts
			(xy 220.98 66.04) (xy 245.11 66.04)
		)
		(stroke
			(width 0)
			(type default)
		)
	)
	(wire
		(pts
			(xy 261.62 55.88) (xy 261.62 68.58)
		)
		(stroke
			(width 0)
			(type default)
		)
	)
	(wire
		(pts
			(xy 88.9 83.82) (xy 93.98 83.82)
		)
		(stroke
			(width 0)
			(type default)
		)
	)
	(wire
		(pts
			(xy 162.56 66.04) (xy 184.15 66.04)
		)
		(stroke
			(width 0)
			(type default)
		)
	)
	(wire
		(pts
			(xy 270.51 143.51) (xy 270.51 142.24)
		)
		(stroke
			(width 0)
			(type default)
		)
	)
	(wire
		(pts
			(xy 262.89 57.15) (xy 292.1 57.15)
		)
		(stroke
			(width 0)
			(type default)
		)
	)
	(wire
		(pts
			(xy 204.47 233.68) (xy 207.01 233.68)
		)
		(stroke
			(width 0)
			(type default)
		)
	)
	(wire
		(pts
			(xy 223.52 224.79) (xy 228.6 224.79)
		)
		(stroke
			(width 0)
			(type default)
		)
	)
	(wire
		(pts
			(xy 269.24 160.02) (xy 254 160.02)
		)
		(stroke
			(width 0)
			(type default)
		)
	)
	(wire
		(pts
			(xy 262.89 71.12) (xy 262.89 69.85)
		)
		(stroke
			(width 0)
			(type default)
		)
	)
	(wire
		(pts
			(xy 195.58 67.31) (xy 195.58 68.58)
		)
		(stroke
			(width 0)
			(type default)
		)
	)
	(wire
		(pts
			(xy 280.67 143.51) (xy 280.67 142.24)
		)
		(stroke
			(width 0)
			(type default)
		)
	)
	(bus
		(pts
			(xy 293.37 91.44) (xy 293.37 93.98)
		)
		(stroke
			(width 0)
			(type default)
		)
	)
	(wire
		(pts
			(xy 255.27 91.44) (xy 262.89 91.44)
		)
		(stroke
			(width 0)
			(type default)
		)
	)
	(wire
		(pts
			(xy 133.35 63.5) (xy 133.35 68.58)
		)
		(stroke
			(width 0)
			(type default)
		)
	)
	(wire
		(pts
			(xy 232.41 55.88) (xy 232.41 68.58)
		)
		(stroke
			(width 0)
			(type default)
		)
	)
	(wire
		(pts
			(xy 261.62 68.58) (xy 261.62 81.28)
		)
		(stroke
			(width 0)
			(type default)
		)
	)
	(wire
		(pts
			(xy 262.89 82.55) (xy 292.1 82.55)
		)
		(stroke
			(width 0)
			(type default)
		)
	)
	(wire
		(pts
			(xy 210.82 53.34) (xy 200.66 53.34)
		)
		(stroke
			(width 0)
			(type default)
		)
	)
	(wire
		(pts
			(xy 241.3 149.86) (xy 233.68 149.86)
		)
		(stroke
			(width 0)
			(type default)
		)
	)
	(wire
		(pts
			(xy 262.89 78.74) (xy 262.89 80.01)
		)
		(stroke
			(width 0)
			(type default)
		)
	)
	(wire
		(pts
			(xy 182.88 154.94) (xy 182.88 158.75)
		)
		(stroke
			(width 0)
			(type default)
		)
	)
	(wire
		(pts
			(xy 241.3 148.59) (xy 241.3 149.86)
		)
		(stroke
			(width 0)
			(type default)
		)
	)
	(wire
		(pts
			(xy 204.47 163.83) (xy 207.01 163.83)
		)
		(stroke
			(width 0)
			(type default)
		)
	)
	(bus
		(pts
			(xy 269.24 168.91) (xy 260.35 168.91)
		)
		(stroke
			(width 0)
			(type default)
		)
	)
	(wire
		(pts
			(xy 200.66 96.52) (xy 200.66 95.25)
		)
		(stroke
			(width 0)
			(type default)
		)
	)
	(wire
		(pts
			(xy 262.89 69.85) (xy 292.1 69.85)
		)
		(stroke
			(width 0)
			(type default)
		)
	)
	(wire
		(pts
			(xy 128.27 52.07) (xy 134.62 52.07)
		)
		(stroke
			(width 0)
			(type default)
		)
	)
	(wire
		(pts
			(xy 232.41 68.58) (xy 232.41 81.28)
		)
		(stroke
			(width 0)
			(type default)
		)
	)
	(bus
		(pts
			(xy 259.08 240.03) (xy 259.08 242.57)
		)
		(stroke
			(width 0)
			(type default)
		)
	)
	(wire
		(pts
			(xy 172.72 179.07) (xy 220.98 179.07)
		)
		(stroke
			(width 0)
			(type default)
		)
	)
	(wire
		(pts
			(xy 255.27 55.88) (xy 261.62 55.88)
		)
		(stroke
			(width 0)
			(type default)
		)
	)
	(wire
		(pts
			(xy 160.02 154.94) (xy 160.02 157.48)
		)
		(stroke
			(width 0)
			(type default)
		)
	)
	(wire
		(pts
			(xy 128.27 66.04) (xy 128.27 68.58)
		)
		(stroke
			(width 0)
			(type default)
		)
	)
	(wire
		(pts
			(xy 195.58 224.79) (xy 195.58 227.33)
		)
		(stroke
			(width 0)
			(type default)
		)
	)
	(wire
		(pts
			(xy 134.62 59.69) (xy 134.62 66.04)
		)
		(stroke
			(width 0)
			(type default)
		)
	)
	(wire
		(pts
			(xy 181.61 95.25) (xy 181.61 81.28)
		)
		(stroke
			(width 0)
			(type default)
		)
	)
	(wire
		(pts
			(xy 220.98 53.34) (xy 245.11 53.34)
		)
		(stroke
			(width 0)
			(type default)
		)
	)
	(wire
		(pts
			(xy 270.51 142.24) (xy 228.6 142.24)
		)
		(stroke
			(width 0)
			(type default)
		)
	)
	(wire
		(pts
			(xy 135.89 189.23) (xy 137.16 189.23)
		)
		(stroke
			(width 0)
			(type default)
		)
	)
	(wire
		(pts
			(xy 142.24 237.49) (xy 135.89 237.49)
		)
		(stroke
			(width 0)
			(type default)
		)
	)
	(wire
		(pts
			(xy 262.89 92.71) (xy 262.89 91.44)
		)
		(stroke
			(width 0)
			(type default)
		)
	)
	(wire
		(pts
			(xy 207.01 160.02) (xy 207.01 163.83)
		)
		(stroke
			(width 0)
			(type default)
		)
	)
	(wire
		(pts
			(xy 93.98 92.71) (xy 86.36 92.71)
		)
		(stroke
			(width 0)
			(type default)
		)
	)
	(wire
		(pts
			(xy 208.28 154.94) (xy 195.58 154.94)
		)
		(stroke
			(width 0)
			(type default)
		)
	)
	(wire
		(pts
			(xy 110.49 74.93) (xy 118.11 74.93)
		)
		(stroke
			(width 0)
			(type default)
		)
	)
	(wire
		(pts
			(xy 82.55 63.5) (xy 90.17 63.5)
		)
		(stroke
			(width 0)
			(type default)
		)
	)
	(wire
		(pts
			(xy 175.26 246.38) (xy 175.26 260.35)
		)
		(stroke
			(width 0)
			(type default)
		)
	)
	(wire
		(pts
			(xy 229.87 241.3) (xy 229.87 247.65)
		)
		(stroke
			(width 0)
			(type default)
		)
	)
	(bus
		(pts
			(xy 293.37 53.34) (xy 293.37 55.88)
		)
		(stroke
			(width 0)
			(type default)
		)
	)
	(wire
		(pts
			(xy 175.26 190.5) (xy 175.26 176.53)
		)
		(stroke
			(width 0)
			(type default)
		)
	)
	(bus
		(pts
			(xy 222.25 180.34) (xy 222.25 177.8)
		)
		(stroke
			(width 0)
			(type default)
		)
	)
	(wire
		(pts
			(xy 269.24 157.48) (xy 254 157.48)
		)
		(stroke
			(width 0)
			(type default)
		)
	)
	(wire
		(pts
			(xy 177.8 254) (xy 177.8 260.35)
		)
		(stroke
			(width 0)
			(type default)
		)
	)
	(wire
		(pts
			(xy 162.56 78.74) (xy 184.15 78.74)
		)
		(stroke
			(width 0)
			(type default)
		)
	)
	(wire
		(pts
			(xy 270.51 214.63) (xy 270.51 212.09)
		)
		(stroke
			(width 0)
			(type default)
		)
	)
	(wire
		(pts
			(xy 261.62 105.41) (xy 261.62 106.68)
		)
		(stroke
			(width 0)
			(type default)
		)
	)
	(wire
		(pts
			(xy 110.49 76.2) (xy 110.49 74.93)
		)
		(stroke
			(width 0)
			(type default)
		)
	)
	(wire
		(pts
			(xy 135.89 254) (xy 177.8 254)
		)
		(stroke
			(width 0)
			(type default)
		)
	)
	(wire
		(pts
			(xy 149.86 224.79) (xy 149.86 227.33)
		)
		(stroke
			(width 0)
			(type default)
		)
	)
	(wire
		(pts
			(xy 200.66 95.25) (xy 181.61 95.25)
		)
		(stroke
			(width 0)
			(type default)
		)
	)
	(wire
		(pts
			(xy 134.62 66.04) (xy 137.16 66.04)
		)
		(stroke
			(width 0)
			(type default)
		)
	)
	(wire
		(pts
			(xy 242.57 68.58) (xy 245.11 68.58)
		)
		(stroke
			(width 0)
			(type default)
		)
	)
	(wire
		(pts
			(xy 262.89 80.01) (xy 292.1 80.01)
		)
		(stroke
			(width 0)
			(type default)
		)
	)
	(wire
		(pts
			(xy 172.72 248.92) (xy 172.72 260.35)
		)
		(stroke
			(width 0)
			(type default)
		)
	)
	(wire
		(pts
			(xy 134.62 50.8) (xy 134.62 52.07)
		)
		(stroke
			(width 0)
			(type default)
		)
	)
	(bus
		(pts
			(xy 260.35 168.91) (xy 259.08 170.18)
		)
		(stroke
			(width 0)
			(type default)
		)
	)
	(wire
		(pts
			(xy 101.6 92.71) (xy 99.06 92.71)
		)
		(stroke
			(width 0)
			(type default)
		)
	)
	(wire
		(pts
			(xy 280.67 212.09) (xy 270.51 212.09)
		)
		(stroke
			(width 0)
			(type default)
		)
	)
	(wire
		(pts
			(xy 261.62 100.33) (xy 261.62 93.98)
		)
		(stroke
			(width 0)
			(type default)
		)
	)
	(wire
		(pts
			(xy 241.3 219.71) (xy 233.68 219.71)
		)
		(stroke
			(width 0)
			(type default)
		)
	)
	(wire
		(pts
			(xy 237.49 55.88) (xy 232.41 55.88)
		)
		(stroke
			(width 0)
			(type default)
		)
	)
	(wire
		(pts
			(xy 128.27 74.93) (xy 133.35 74.93)
		)
		(stroke
			(width 0)
			(type default)
		)
	)
	(wire
		(pts
			(xy 135.89 248.92) (xy 172.72 248.92)
		)
		(stroke
			(width 0)
			(type default)
		)
	)
	(wire
		(pts
			(xy 172.72 179.07) (xy 172.72 190.5)
		)
		(stroke
			(width 0)
			(type default)
		)
	)
	(bus
		(pts
			(xy 222.25 256.54) (xy 222.25 255.27)
		)
		(stroke
			(width 0)
			(type default)
		)
	)
	(wire
		(pts
			(xy 137.16 256.54) (xy 137.16 259.08)
		)
		(stroke
			(width 0)
			(type default)
		)
	)
	(wire
		(pts
			(xy 233.68 157.48) (xy 223.52 157.48)
		)
		(stroke
			(width 0)
			(type default)
		)
	)
	(wire
		(pts
			(xy 160.02 154.94) (xy 182.88 154.94)
		)
		(stroke
			(width 0)
			(type default)
		)
	)
	(wire
		(pts
			(xy 200.66 78.74) (xy 210.82 78.74)
		)
		(stroke
			(width 0)
			(type default)
		)
	)
	(wire
		(pts
			(xy 82.55 86.36) (xy 86.36 86.36)
		)
		(stroke
			(width 0)
			(type default)
		)
	)
	(wire
		(pts
			(xy 208.28 229.87) (xy 207.01 229.87)
		)
		(stroke
			(width 0)
			(type default)
		)
	)
	(wire
		(pts
			(xy 184.15 57.15) (xy 184.15 66.04)
		)
		(stroke
			(width 0)
			(type default)
		)
	)
	(wire
		(pts
			(xy 200.66 71.12) (xy 210.82 71.12)
		)
		(stroke
			(width 0)
			(type default)
		)
	)
	(wire
		(pts
			(xy 248.92 157.48) (xy 233.68 157.48)
		)
		(stroke
			(width 0)
			(type default)
		)
	)
	(wire
		(pts
			(xy 255.27 66.04) (xy 262.89 66.04)
		)
		(stroke
			(width 0)
			(type default)
		)
	)
	(wire
		(pts
			(xy 200.66 69.85) (xy 200.66 71.12)
		)
		(stroke
			(width 0)
			(type default)
		)
	)
	(wire
		(pts
			(xy 200.66 53.34) (xy 200.66 54.61)
		)
		(stroke
			(width 0)
			(type default)
		)
	)
	(wire
		(pts
			(xy 255.27 68.58) (xy 261.62 68.58)
		)
		(stroke
			(width 0)
			(type default)
		)
	)
	(wire
		(pts
			(xy 229.87 241.3) (xy 135.89 241.3)
		)
		(stroke
			(width 0)
			(type default)
		)
	)
	(wire
		(pts
			(xy 242.57 81.28) (xy 245.11 81.28)
		)
		(stroke
			(width 0)
			(type default)
		)
	)
	(wire
		(pts
			(xy 270.51 212.09) (xy 228.6 212.09)
		)
		(stroke
			(width 0)
			(type default)
		)
	)
	(wire
		(pts
			(xy 160.02 106.68) (xy 163.83 106.68)
		)
		(stroke
			(width 0)
			(type default)
		)
	)
	(wire
		(pts
			(xy 270.51 148.59) (xy 270.51 149.86)
		)
		(stroke
			(width 0)
			(type default)
		)
	)
	(bus
		(pts
			(xy 293.37 48.26) (xy 293.37 53.34)
		)
		(stroke
			(width 0)
			(type default)
		)
	)
	(wire
		(pts
			(xy 233.68 219.71) (xy 233.68 220.98)
		)
		(stroke
			(width 0)
			(type default)
		)
	)
	(wire
		(pts
			(xy 93.98 66.04) (xy 90.17 66.04)
		)
		(stroke
			(width 0)
			(type default)
		)
	)
	(wire
		(pts
			(xy 255.27 93.98) (xy 261.62 93.98)
		)
		(stroke
			(width 0)
			(type default)
		)
	)
	(wire
		(pts
			(xy 255.27 83.82) (xy 262.89 83.82)
		)
		(stroke
			(width 0)
			(type default)
		)
	)
	(wire
		(pts
			(xy 181.61 54.61) (xy 200.66 54.61)
		)
		(stroke
			(width 0)
			(type default)
		)
	)
	(wire
		(pts
			(xy 261.62 81.28) (xy 261.62 93.98)
		)
		(stroke
			(width 0)
			(type default)
		)
	)
	(wire
		(pts
			(xy 109.22 86.36) (xy 109.22 92.71)
		)
		(stroke
			(width 0)
			(type default)
		)
	)
	(wire
		(pts
			(xy 232.41 93.98) (xy 232.41 100.33)
		)
		(stroke
			(width 0)
			(type default)
		)
	)
	(wire
		(pts
			(xy 142.24 237.49) (xy 142.24 224.79)
		)
		(stroke
			(width 0)
			(type default)
		)
	)
	(wire
		(pts
			(xy 233.68 227.33) (xy 233.68 226.06)
		)
		(stroke
			(width 0)
			(type default)
		)
	)
	(wire
		(pts
			(xy 99.06 83.82) (xy 106.68 83.82)
		)
		(stroke
			(width 0)
			(type default)
		)
	)
	(wire
		(pts
			(xy 160.02 224.79) (xy 160.02 227.33)
		)
		(stroke
			(width 0)
			(type default)
		)
	)
	(wire
		(pts
			(xy 248.92 227.33) (xy 233.68 227.33)
		)
		(stroke
			(width 0)
			(type default)
		)
	)
	(bus
		(pts
			(xy 294.64 43.18) (xy 299.72 43.18)
		)
		(stroke
			(width 0)
			(type default)
		)
	)
	(wire
		(pts
			(xy 204.47 232.41) (xy 204.47 233.68)
		)
		(stroke
			(width 0)
			(type default)
		)
	)
	(wire
		(pts
			(xy 269.24 227.33) (xy 254 227.33)
		)
		(stroke
			(width 0)
			(type default)
		)
	)
	(wire
		(pts
			(xy 118.11 81.28) (xy 118.11 86.36)
		)
		(stroke
			(width 0)
			(type default)
		)
	)
	(wire
		(pts
			(xy 262.89 92.71) (xy 292.1 92.71)
		)
		(stroke
			(width 0)
			(type default)
		)
	)
	(wire
		(pts
			(xy 280.67 212.09) (xy 280.67 214.63)
		)
		(stroke
			(width 0)
			(type default)
		)
	)
	(wire
		(pts
			(xy 137.16 259.08) (xy 137.16 260.35)
		)
		(stroke
			(width 0)
			(type default)
		)
	)
	(wire
		(pts
			(xy 241.3 160.02) (xy 223.52 160.02)
		)
		(stroke
			(width 0)
			(type default)
		)
	)
	(bus
		(pts
			(xy 293.37 68.58) (xy 293.37 78.74)
		)
		(stroke
			(width 0)
			(type default)
		)
	)
	(wire
		(pts
			(xy 229.87 241.3) (xy 233.68 241.3)
		)
		(stroke
			(width 0)
			(type default)
		)
	)
	(wire
		(pts
			(xy 137.16 186.69) (xy 137.16 189.23)
		)
		(stroke
			(width 0)
			(type default)
		)
	)
	(wire
		(pts
			(xy 255.27 58.42) (xy 262.89 58.42)
		)
		(stroke
			(width 0)
			(type default)
		)
	)
	(wire
		(pts
			(xy 210.82 91.44) (xy 200.66 91.44)
		)
		(stroke
			(width 0)
			(type default)
		)
	)
	(wire
		(pts
			(xy 223.52 154.94) (xy 228.6 154.94)
		)
		(stroke
			(width 0)
			(type default)
		)
	)
	(wire
		(pts
			(xy 175.26 246.38) (xy 220.98 246.38)
		)
		(stroke
			(width 0)
			(type default)
		)
	)
	(wire
		(pts
			(xy 175.26 176.53) (xy 220.98 176.53)
		)
		(stroke
			(width 0)
			(type default)
		)
	)
	(wire
		(pts
			(xy 280.67 55.88) (xy 280.67 100.33)
		)
		(stroke
			(width 0)
			(type default)
		)
	)
	(wire
		(pts
			(xy 162.56 81.28) (xy 181.61 81.28)
		)
		(stroke
			(width 0)
			(type default)
		)
	)
	(wire
		(pts
			(xy 110.49 83.82) (xy 137.16 83.82)
		)
		(stroke
			(width 0)
			(type default)
		)
	)
	(wire
		(pts
			(xy 104.14 92.71) (xy 109.22 92.71)
		)
		(stroke
			(width 0)
			(type default)
		)
	)
	(wire
		(pts
			(xy 274.32 100.33) (xy 274.32 68.58)
		)
		(stroke
			(width 0)
			(type default)
		)
	)
	(wire
		(pts
			(xy 142.24 154.94) (xy 149.86 154.94)
		)
		(stroke
			(width 0)
			(type default)
		)
	)
	(wire
		(pts
			(xy 180.34 251.46) (xy 180.34 260.35)
		)
		(stroke
			(width 0)
			(type default)
		)
	)
	(wire
		(pts
			(xy 86.36 92.71) (xy 86.36 86.36)
		)
		(stroke
			(width 0)
			(type default)
		)
	)
	(bus
		(pts
			(xy 293.37 78.74) (xy 293.37 81.28)
		)
		(stroke
			(width 0)
			(type default)
		)
	)
	(wire
		(pts
			(xy 149.86 163.83) (xy 149.86 162.56)
		)
		(stroke
			(width 0)
			(type default)
		)
	)
	(wire
		(pts
			(xy 248.92 229.87) (xy 241.3 229.87)
		)
		(stroke
			(width 0)
			(type default)
		)
	)
	(wire
		(pts
			(xy 190.5 82.55) (xy 200.66 82.55)
		)
		(stroke
			(width 0)
			(type default)
		)
	)
	(wire
		(pts
			(xy 177.8 184.15) (xy 220.98 184.15)
		)
		(stroke
			(width 0)
			(type default)
		)
	)
	(bus
		(pts
			(xy 269.24 238.76) (xy 260.35 238.76)
		)
		(stroke
			(width 0)
			(type default)
		)
	)
	(wire
		(pts
			(xy 242.57 55.88) (xy 245.11 55.88)
		)
		(stroke
			(width 0)
			(type default)
		)
	)
	(bus
		(pts
			(xy 223.52 187.96) (xy 222.25 186.69)
		)
		(stroke
			(width 0)
			(type default)
		)
	)
	(wire
		(pts
			(xy 220.98 91.44) (xy 245.11 91.44)
		)
		(stroke
			(width 0)
			(type default)
		)
	)
	(wire
		(pts
			(xy 135.89 176.53) (xy 175.26 176.53)
		)
		(stroke
			(width 0)
			(type default)
		)
	)
	(wire
		(pts
			(xy 163.83 106.68) (xy 163.83 107.95)
		)
		(stroke
			(width 0)
			(type default)
		)
	)
	(wire
		(pts
			(xy 255.27 71.12) (xy 262.89 71.12)
		)
		(stroke
			(width 0)
			(type default)
		)
	)
	(wire
		(pts
			(xy 261.62 55.88) (xy 261.62 49.53)
		)
		(stroke
			(width 0)
			(type default)
		)
	)
	(wire
		(pts
			(xy 135.89 181.61) (xy 180.34 181.61)
		)
		(stroke
			(width 0)
			(type default)
		)
	)
	(wire
		(pts
			(xy 193.04 71.12) (xy 193.04 80.01)
		)
		(stroke
			(width 0)
			(type default)
		)
	)
	(wire
		(pts
			(xy 118.11 86.36) (xy 137.16 86.36)
		)
		(stroke
			(width 0)
			(type default)
		)
	)
	(wire
		(pts
			(xy 99.06 66.04) (xy 128.27 66.04)
		)
		(stroke
			(width 0)
			(type default)
		)
	)
	(wire
		(pts
			(xy 208.28 224.79) (xy 195.58 224.79)
		)
		(stroke
			(width 0)
			(type default)
		)
	)
	(wire
		(pts
			(xy 241.3 229.87) (xy 223.52 229.87)
		)
		(stroke
			(width 0)
			(type default)
		)
	)
	(wire
		(pts
			(xy 227.33 173.99) (xy 233.68 173.99)
		)
		(stroke
			(width 0)
			(type default)
		)
	)
	(wire
		(pts
			(xy 195.58 154.94) (xy 195.58 157.48)
		)
		(stroke
			(width 0)
			(type default)
		)
	)
	(wire
		(pts
			(xy 135.89 179.07) (xy 172.72 179.07)
		)
		(stroke
			(width 0)
			(type default)
		)
	)
	(wire
		(pts
			(xy 257.81 171.45) (xy 238.76 171.45)
		)
		(stroke
			(width 0)
			(type default)
		)
	)
	(wire
		(pts
			(xy 181.61 63.5) (xy 181.61 54.61)
		)
		(stroke
			(width 0)
			(type default)
		)
	)
	(wire
		(pts
			(xy 160.02 233.68) (xy 160.02 232.41)
		)
		(stroke
			(width 0)
			(type default)
		)
	)
	(wire
		(pts
			(xy 135.89 184.15) (xy 177.8 184.15)
		)
		(stroke
			(width 0)
			(type default)
		)
	)
	(wire
		(pts
			(xy 99.06 63.5) (xy 128.27 63.5)
		)
		(stroke
			(width 0)
			(type default)
		)
	)
	(wire
		(pts
			(xy 200.66 67.31) (xy 195.58 67.31)
		)
		(stroke
			(width 0)
			(type default)
		)
	)
	(wire
		(pts
			(xy 207.01 229.87) (xy 207.01 233.68)
		)
		(stroke
			(width 0)
			(type default)
		)
	)
	(bus
		(pts
			(xy 223.52 257.81) (xy 222.25 256.54)
		)
		(stroke
			(width 0)
			(type default)
		)
	)
	(wire
		(pts
			(xy 267.97 81.28) (xy 261.62 81.28)
		)
		(stroke
			(width 0)
			(type default)
		)
	)
	(wire
		(pts
			(xy 184.15 92.71) (xy 200.66 92.71)
		)
		(stroke
			(width 0)
			(type default)
		)
	)
	(wire
		(pts
			(xy 177.8 184.15) (xy 177.8 190.5)
		)
		(stroke
			(width 0)
			(type default)
		)
	)
	(wire
		(pts
			(xy 241.3 151.13) (xy 241.3 149.86)
		)
		(stroke
			(width 0)
			(type default)
		)
	)
	(wire
		(pts
			(xy 275.59 49.53) (xy 292.1 49.53)
		)
		(stroke
			(width 0)
			(type default)
		)
	)
	(wire
		(pts
			(xy 187.96 259.08) (xy 182.88 259.08)
		)
		(stroke
			(width 0)
			(type default)
		)
	)
	(wire
		(pts
			(xy 204.47 162.56) (xy 204.47 163.83)
		)
		(stroke
			(width 0)
			(type default)
		)
	)
	(wire
		(pts
			(xy 160.02 224.79) (xy 182.88 224.79)
		)
		(stroke
			(width 0)
			(type default)
		)
	)
	(wire
		(pts
			(xy 233.68 157.48) (xy 233.68 156.21)
		)
		(stroke
			(width 0)
			(type default)
		)
	)
	(wire
		(pts
			(xy 163.83 86.36) (xy 163.83 92.71)
		)
		(stroke
			(width 0)
			(type default)
		)
	)
	(wire
		(pts
			(xy 162.56 76.2) (xy 198.12 76.2)
		)
		(stroke
			(width 0)
			(type default)
		)
	)
	(wire
		(pts
			(xy 210.82 96.52) (xy 200.66 96.52)
		)
		(stroke
			(width 0)
			(type default)
		)
	)
	(wire
		(pts
			(xy 262.89 67.31) (xy 292.1 67.31)
		)
		(stroke
			(width 0)
			(type default)
		)
	)
	(wire
		(pts
			(xy 137.16 189.23) (xy 137.16 190.5)
		)
		(stroke
			(width 0)
			(type default)
		)
	)
	(wire
		(pts
			(xy 135.89 259.08) (xy 137.16 259.08)
		)
		(stroke
			(width 0)
			(type default)
		)
	)
	(wire
		(pts
			(xy 93.98 90.17) (xy 88.9 90.17)
		)
		(stroke
			(width 0)
			(type default)
		)
	)
	(wire
		(pts
			(xy 90.17 66.04) (xy 90.17 63.5)
		)
		(stroke
			(width 0)
			(type default)
		)
	)
	(wire
		(pts
			(xy 160.02 92.71) (xy 163.83 92.71)
		)
		(stroke
			(width 0)
			(type default)
		)
	)
	(bus
		(pts
			(xy 222.25 252.73) (xy 222.25 255.27)
		)
		(stroke
			(width 0)
			(type default)
		)
	)
	(wire
		(pts
			(xy 180.34 251.46) (xy 220.98 251.46)
		)
		(stroke
			(width 0)
			(type default)
		)
	)
	(wire
		(pts
			(xy 101.6 90.17) (xy 99.06 90.17)
		)
		(stroke
			(width 0)
			(type default)
		)
	)
	(wire
		(pts
			(xy 280.67 148.59) (xy 280.67 149.86)
		)
		(stroke
			(width 0)
			(type default)
		)
	)
	(wire
		(pts
			(xy 182.88 259.08) (xy 182.88 260.35)
		)
		(stroke
			(width 0)
			(type default)
		)
	)
	(wire
		(pts
			(xy 180.34 181.61) (xy 220.98 181.61)
		)
		(stroke
			(width 0)
			(type default)
		)
	)
	(bus
		(pts
			(xy 294.64 43.18) (xy 293.37 44.45)
		)
		(stroke
			(width 0)
			(type default)
		)
	)
	(bus
		(pts
			(xy 222.25 250.19) (xy 222.25 247.65)
		)
		(stroke
			(width 0)
			(type default)
		)
	)
	(wire
		(pts
			(xy 128.27 66.04) (xy 134.62 66.04)
		)
		(stroke
			(width 0)
			(type default)
		)
	)
	(wire
		(pts
			(xy 162.56 68.58) (xy 195.58 68.58)
		)
		(stroke
			(width 0)
			(type default)
		)
	)
	(wire
		(pts
			(xy 182.88 232.41) (xy 182.88 233.68)
		)
		(stroke
			(width 0)
			(type default)
		)
	)
	(wire
		(pts
			(xy 280.67 210.82) (xy 280.67 212.09)
		)
		(stroke
			(width 0)
			(type default)
		)
	)
	(wire
		(pts
			(xy 262.89 96.52) (xy 262.89 95.25)
		)
		(stroke
			(width 0)
			(type default)
		)
	)
	(wire
		(pts
			(xy 142.24 167.64) (xy 142.24 154.94)
		)
		(stroke
			(width 0)
			(type default)
		)
	)
	(wire
		(pts
			(xy 229.87 171.45) (xy 233.68 171.45)
		)
		(stroke
			(width 0)
			(type default)
		)
	)
	(wire
		(pts
			(xy 104.14 90.17) (xy 106.68 90.17)
		)
		(stroke
			(width 0)
			(type default)
		)
	)
	(wire
		(pts
			(xy 210.82 58.42) (xy 200.66 58.42)
		)
		(stroke
			(width 0)
			(type default)
		)
	)
	(bus
		(pts
			(xy 259.08 170.18) (xy 259.08 172.72)
		)
		(stroke
			(width 0)
			(type default)
		)
	)
	(wire
		(pts
			(xy 135.89 186.69) (xy 137.16 186.69)
		)
		(stroke
			(width 0)
			(type default)
		)
	)
	(wire
		(pts
			(xy 104.14 92.71) (xy 101.6 90.17)
		)
		(stroke
			(width 0)
			(type default)
		)
	)
	(wire
		(pts
			(xy 210.82 83.82) (xy 200.66 83.82)
		)
		(stroke
			(width 0)
			(type default)
		)
	)
	(wire
		(pts
			(xy 133.35 63.5) (xy 137.16 63.5)
		)
		(stroke
			(width 0)
			(type default)
		)
	)
	(wire
		(pts
			(xy 177.8 254) (xy 220.98 254)
		)
		(stroke
			(width 0)
			(type default)
		)
	)
	(wire
		(pts
			(xy 160.02 163.83) (xy 160.02 162.56)
		)
		(stroke
			(width 0)
			(type default)
		)
	)
	(wire
		(pts
			(xy 232.41 81.28) (xy 232.41 93.98)
		)
		(stroke
			(width 0)
			(type default)
		)
	)
	(wire
		(pts
			(xy 208.28 157.48) (xy 204.47 157.48)
		)
		(stroke
			(width 0)
			(type default)
		)
	)
	(wire
		(pts
			(xy 262.89 66.04) (xy 262.89 67.31)
		)
		(stroke
			(width 0)
			(type default)
		)
	)
	(wire
		(pts
			(xy 90.17 63.5) (xy 93.98 63.5)
		)
		(stroke
			(width 0)
			(type default)
		)
	)
	(wire
		(pts
			(xy 110.49 73.66) (xy 110.49 74.93)
		)
		(stroke
			(width 0)
			(type default)
		)
	)
	(wire
		(pts
			(xy 261.62 55.88) (xy 280.67 55.88)
		)
		(stroke
			(width 0)
			(type default)
		)
	)
	(wire
		(pts
			(xy 242.57 93.98) (xy 245.11 93.98)
		)
		(stroke
			(width 0)
			(type default)
		)
	)
	(wire
		(pts
			(xy 227.33 173.99) (xy 135.89 173.99)
		)
		(stroke
			(width 0)
			(type default)
		)
	)
	(wire
		(pts
			(xy 233.68 149.86) (xy 233.68 151.13)
		)
		(stroke
			(width 0)
			(type default)
		)
	)
	(wire
		(pts
			(xy 82.55 83.82) (xy 88.9 83.82)
		)
		(stroke
			(width 0)
			(type default)
		)
	)
	(bus
		(pts
			(xy 293.37 81.28) (xy 293.37 91.44)
		)
		(stroke
			(width 0)
			(type default)
		)
	)
	(bus
		(pts
			(xy 269.24 257.81) (xy 223.52 257.81)
		)
		(stroke
			(width 0)
			(type default)
		)
	)
	(wire
		(pts
			(xy 232.41 81.28) (xy 237.49 81.28)
		)
		(stroke
			(width 0)
			(type default)
		)
	)
	(wire
		(pts
			(xy 255.27 78.74) (xy 262.89 78.74)
		)
		(stroke
			(width 0)
			(type default)
		)
	)
	(wire
		(pts
			(xy 86.36 86.36) (xy 93.98 86.36)
		)
		(stroke
			(width 0)
			(type default)
		)
	)
	(wire
		(pts
			(xy 163.83 106.68) (xy 163.83 102.87)
		)
		(stroke
			(width 0)
			(type default)
		)
	)
	(wire
		(pts
			(xy 106.68 83.82) (xy 110.49 83.82)
		)
		(stroke
			(width 0)
			(type default)
		)
	)
	(wire
		(pts
			(xy 187.96 190.5) (xy 187.96 189.23)
		)
		(stroke
			(width 0)
			(type default)
		)
	)
	(wire
		(pts
			(xy 267.97 105.41) (xy 267.97 106.68)
		)
		(stroke
			(width 0)
			(type default)
		)
	)
	(wire
		(pts
			(xy 255.27 81.28) (xy 261.62 81.28)
		)
		(stroke
			(width 0)
			(type default)
		)
	)
	(wire
		(pts
			(xy 195.58 154.94) (xy 182.88 154.94)
		)
		(stroke
			(width 0)
			(type default)
		)
	)
	(wire
		(pts
			(xy 261.62 49.53) (xy 270.51 49.53)
		)
		(stroke
			(width 0)
			(type default)
		)
	)
	(wire
		(pts
			(xy 200.66 80.01) (xy 193.04 80.01)
		)
		(stroke
			(width 0)
			(type default)
		)
	)
	(wire
		(pts
			(xy 229.87 171.45) (xy 229.87 176.53)
		)
		(stroke
			(width 0)
			(type default)
		)
	)
	(wire
		(pts
			(xy 269.24 229.87) (xy 254 229.87)
		)
		(stroke
			(width 0)
			(type default)
		)
	)
	(wire
		(pts
			(xy 232.41 247.65) (xy 232.41 245.11)
		)
		(stroke
			(width 0)
			(type default)
		)
	)
	(wire
		(pts
			(xy 255.27 53.34) (xy 262.89 53.34)
		)
		(stroke
			(width 0)
			(type default)
		)
	)
	(wire
		(pts
			(xy 274.32 105.41) (xy 274.32 106.68)
		)
		(stroke
			(width 0)
			(type default)
		)
	)
	(bus
		(pts
			(xy 293.37 44.45) (xy 293.37 48.26)
		)
		(stroke
			(width 0)
			(type default)
		)
	)
	(wire
		(pts
			(xy 110.49 81.28) (xy 110.49 83.82)
		)
		(stroke
			(width 0)
			(type default)
		)
	)
	(wire
		(pts
			(xy 118.11 74.93) (xy 118.11 76.2)
		)
		(stroke
			(width 0)
			(type default)
		)
	)
	(wire
		(pts
			(xy 241.3 226.06) (xy 241.3 229.87)
		)
		(stroke
			(width 0)
			(type default)
		)
	)
	(wire
		(pts
			(xy 198.12 69.85) (xy 198.12 76.2)
		)
		(stroke
			(width 0)
			(type default)
		)
	)
	(wire
		(pts
			(xy 142.24 167.64) (xy 135.89 167.64)
		)
		(stroke
			(width 0)
			(type default)
		)
	)
	(wire
		(pts
			(xy 149.86 154.94) (xy 160.02 154.94)
		)
		(stroke
			(width 0)
			(type default)
		)
	)
	(wire
		(pts
			(xy 160.02 97.79) (xy 160.02 92.71)
		)
		(stroke
			(width 0)
			(type default)
		)
	)
	(wire
		(pts
			(xy 109.22 86.36) (xy 118.11 86.36)
		)
		(stroke
			(width 0)
			(type default)
		)
	)
	(wire
		(pts
			(xy 187.96 189.23) (xy 182.88 189.23)
		)
		(stroke
			(width 0)
			(type default)
		)
	)
	(wire
		(pts
			(xy 200.66 83.82) (xy 200.66 82.55)
		)
		(stroke
			(width 0)
			(type default)
		)
	)
	(wire
		(pts
			(xy 195.58 224.79) (xy 182.88 224.79)
		)
		(stroke
			(width 0)
			(type default)
		)
	)
	(wire
		(pts
			(xy 133.35 73.66) (xy 133.35 74.93)
		)
		(stroke
			(width 0)
			(type default)
		)
	)
	(wire
		(pts
			(xy 184.15 78.74) (xy 184.15 92.71)
		)
		(stroke
			(width 0)
			(type default)
		)
	)
	(wire
		(pts
			(xy 262.89 53.34) (xy 262.89 54.61)
		)
		(stroke
			(width 0)
			(type default)
		)
	)
	(wire
		(pts
			(xy 128.27 63.5) (xy 133.35 63.5)
		)
		(stroke
			(width 0)
			(type default)
		)
	)
	(wire
		(pts
			(xy 232.41 105.41) (xy 232.41 106.68)
		)
		(stroke
			(width 0)
			(type default)
		)
	)
	(wire
		(pts
			(xy 135.89 256.54) (xy 137.16 256.54)
		)
		(stroke
			(width 0)
			(type default)
		)
	)
	(wire
		(pts
			(xy 162.56 63.5) (xy 181.61 63.5)
		)
		(stroke
			(width 0)
			(type default)
		)
	)
	(wire
		(pts
			(xy 227.33 243.84) (xy 233.68 243.84)
		)
		(stroke
			(width 0)
			(type default)
		)
	)
	(wire
		(pts
			(xy 232.41 68.58) (xy 237.49 68.58)
		)
		(stroke
			(width 0)
			(type default)
		)
	)
	(wire
		(pts
			(xy 232.41 245.11) (xy 237.49 245.11)
		)
		(stroke
			(width 0)
			(type default)
		)
	)
	(wire
		(pts
			(xy 200.66 58.42) (xy 200.66 57.15)
		)
		(stroke
			(width 0)
			(type default)
		)
	)
	(wire
		(pts
			(xy 190.5 82.55) (xy 190.5 73.66)
		)
		(stroke
			(width 0)
			(type default)
		)
	)
	(wire
		(pts
			(xy 280.67 140.97) (xy 280.67 142.24)
		)
		(stroke
			(width 0)
			(type default)
		)
	)
	(wire
		(pts
			(xy 163.83 97.79) (xy 163.83 92.71)
		)
		(stroke
			(width 0)
			(type default)
		)
	)
	(wire
		(pts
			(xy 149.86 233.68) (xy 149.86 232.41)
		)
		(stroke
			(width 0)
			(type default)
		)
	)
	(bus
		(pts
			(xy 293.37 66.04) (xy 293.37 68.58)
		)
		(stroke
			(width 0)
			(type default)
		)
	)
	(wire
		(pts
			(xy 220.98 78.74) (xy 245.11 78.74)
		)
		(stroke
			(width 0)
			(type default)
		)
	)
	(wire
		(pts
			(xy 227.33 243.84) (xy 135.89 243.84)
		)
		(stroke
			(width 0)
			(type default)
		)
	)
	(wire
		(pts
			(xy 128.27 59.69) (xy 128.27 63.5)
		)
		(stroke
			(width 0)
			(type default)
		)
	)
	(wire
		(pts
			(xy 160.02 106.68) (xy 160.02 102.87)
		)
		(stroke
			(width 0)
			(type default)
		)
	)
	(wire
		(pts
			(xy 142.24 224.79) (xy 149.86 224.79)
		)
		(stroke
			(width 0)
			(type default)
		)
	)
	(wire
		(pts
			(xy 233.68 227.33) (xy 223.52 227.33)
		)
		(stroke
			(width 0)
			(type default)
		)
	)
	(wire
		(pts
			(xy 101.6 92.71) (xy 104.14 90.17)
		)
		(stroke
			(width 0)
			(type default)
		)
	)
	(wire
		(pts
			(xy 195.58 163.83) (xy 195.58 162.56)
		)
		(stroke
			(width 0)
			(type default)
		)
	)
	(wire
		(pts
			(xy 220.98 71.12) (xy 245.11 71.12)
		)
		(stroke
			(width 0)
			(type default)
		)
	)
	(wire
		(pts
			(xy 274.32 68.58) (xy 261.62 68.58)
		)
		(stroke
			(width 0)
			(type default)
		)
	)
	(wire
		(pts
			(xy 149.86 224.79) (xy 160.02 224.79)
		)
		(stroke
			(width 0)
			(type default)
		)
	)
	(wire
		(pts
			(xy 134.62 52.07) (xy 134.62 54.61)
		)
		(stroke
			(width 0)
			(type default)
		)
	)
	(wire
		(pts
			(xy 200.66 78.74) (xy 200.66 80.01)
		)
		(stroke
			(width 0)
			(type default)
		)
	)
	(label "DB-"
		(at 205.74 71.12 180)
		(effects
			(font
				(size 1.27 1.27)
			)
			(justify right bottom)
		)
	)
	(label "P1_D-"
		(at 173.99 173.99 180)
		(effects
			(font
				(size 1.27 1.27)
			)
			(justify right bottom)
		)
	)
	(label "P2_VBUS"
		(at 173.99 224.79 180)
		(effects
			(font
				(size 1.27 1.27)
			)
			(justify right bottom)
		)
	)
	(label "DA_FL+"
		(at 231.14 53.34 180)
		(effects
			(font
				(size 1.27 1.27)
			)
			(justify right bottom)
		)
	)
	(label "P2_ISET"
		(at 208.28 227.33 180)
		(effects
			(font
				(size 1.27 1.27)
			)
			(justify right bottom)
		)
	)
	(label "P2_D+"
		(at 173.99 241.3 180)
		(effects
			(font
				(size 1.27 1.27)
			)
			(justify right bottom)
		)
	)
	(label "DB_FL-"
		(at 231.14 71.12 180)
		(effects
			(font
				(size 1.27 1.27)
			)
			(justify right bottom)
		)
	)
	(label "FLG_2B"
		(at 229.87 227.33 180)
		(effects
			(font
				(size 1.27 1.27)
			)
			(justify right bottom)
		)
	)
	(label "P1_ISET"
		(at 208.28 157.48 180)
		(effects
			(font
				(size 1.27 1.27)
			)
			(justify right bottom)
		)
	)
	(label "USBSS_1.TX-"
		(at 205.74 184.15 0)
		(effects
			(font
				(size 1.27 1.27)
			)
			(justify left bottom)
		)
	)
	(label "USBSS_2.RX-"
		(at 217.17 248.92 180)
		(effects
			(font
				(size 1.27 1.27)
			)
			(justify right bottom)
		)
	)
	(label "DC+"
		(at 170.18 71.12 180)
		(effects
			(font
				(size 1.27 1.27)
			)
			(justify right bottom)
		)
	)
	(label "DC_FL-"
		(at 231.14 83.82 180)
		(effects
			(font
				(size 1.27 1.27)
			)
			(justify right bottom)
		)
	)
	(label "DD+"
		(at 170.18 78.74 180)
		(effects
			(font
				(size 1.27 1.27)
			)
			(justify right bottom)
		)
	)
	(label "DA_FL-"
		(at 231.14 58.42 180)
		(effects
			(font
				(size 1.27 1.27)
			)
			(justify right bottom)
		)
	)
	(label "USBSS_1.TX+"
		(at 205.74 181.61 0)
		(effects
			(font
				(size 1.27 1.27)
			)
			(justify left bottom)
		)
	)
	(label "SH"
		(at 162.56 92.71 180)
		(effects
			(font
				(size 1.27 1.27)
			)
			(justify right bottom)
		)
	)
	(label "FLG_1B"
		(at 229.87 157.48 180)
		(effects
			(font
				(size 1.27 1.27)
			)
			(justify right bottom)
		)
	)
	(label "GbE.MDI2-"
		(at 281.94 82.55 0)
		(effects
			(font
				(size 1.27 1.27)
			)
			(justify left bottom)
		)
	)
	(label "USBSS_2.TX-"
		(at 205.74 254 0)
		(effects
			(font
				(size 1.27 1.27)
			)
			(justify left bottom)
		)
	)
	(label "DD-"
		(at 170.18 81.28 180)
		(effects
			(font
				(size 1.27 1.27)
			)
			(justify right bottom)
		)
	)
	(label "DC+"
		(at 205.74 78.74 180)
		(effects
			(font
				(size 1.27 1.27)
			)
			(justify right bottom)
		)
	)
	(label "USBSS_1.RX-"
		(at 217.17 179.07 180)
		(effects
			(font
				(size 1.27 1.27)
			)
			(justify right bottom)
		)
	)
	(label "GbE.MDI3+"
		(at 281.94 92.71 0)
		(effects
			(font
				(size 1.27 1.27)
			)
			(justify left bottom)
		)
	)
	(label "EN_2B"
		(at 229.87 229.87 180)
		(effects
			(font
				(size 1.27 1.27)
			)
			(justify right bottom)
		)
	)
	(label "GbE.MDI0-"
		(at 281.94 57.15 0)
		(effects
			(font
				(size 1.27 1.27)
			)
			(justify left bottom)
		)
	)
	(label "P1_D+"
		(at 173.99 171.45 180)
		(effects
			(font
				(size 1.27 1.27)
			)
			(justify right bottom)
		)
	)
	(label "DD+"
		(at 205.74 91.44 180)
		(effects
			(font
				(size 1.27 1.27)
			)
			(justify right bottom)
		)
	)
	(label "USB_1.D+"
		(at 255.27 171.45 180)
		(effects
			(font
				(size 1.27 1.27)
			)
			(justify right bottom)
		)
	)
	(label "DD_FL+"
		(at 231.14 91.44 180)
		(effects
			(font
				(size 1.27 1.27)
			)
			(justify right bottom)
		)
	)
	(label "DC-"
		(at 205.74 83.82 180)
		(effects
			(font
				(size 1.27 1.27)
			)
			(justify right bottom)
		)
	)
	(label "GbE.CTREF"
		(at 281.94 49.53 0)
		(effects
			(font
				(size 1.27 1.27)
			)
			(justify left bottom)
		)
	)
	(label "USB_2.D+"
		(at 255.27 241.3 180)
		(effects
			(font
				(size 1.27 1.27)
			)
			(justify right bottom)
		)
	)
	(label "USBSS_2.TX+"
		(at 205.74 251.46 0)
		(effects
			(font
				(size 1.27 1.27)
			)
			(justify left bottom)
		)
	)
	(label "GbE.MDI2+"
		(at 281.94 80.01 0)
		(effects
			(font
				(size 1.27 1.27)
			)
			(justify left bottom)
		)
	)
	(label "DB_FL+"
		(at 231.14 66.04 180)
		(effects
			(font
				(size 1.27 1.27)
			)
			(justify right bottom)
		)
	)
	(label "DA+"
		(at 170.18 63.5 180)
		(effects
			(font
				(size 1.27 1.27)
			)
			(justify right bottom)
		)
	)
	(label "DB-"
		(at 170.18 76.2 180)
		(effects
			(font
				(size 1.27 1.27)
			)
			(justify right bottom)
		)
	)
	(label "USB_1.D-"
		(at 255.27 173.99 180)
		(effects
			(font
				(size 1.27 1.27)
			)
			(justify right bottom)
		)
	)
	(label "DD-"
		(at 205.74 96.52 180)
		(effects
			(font
				(size 1.27 1.27)
			)
			(justify right bottom)
		)
	)
	(label "GbE.MDI3-"
		(at 281.94 95.25 0)
		(effects
			(font
				(size 1.27 1.27)
			)
			(justify left bottom)
		)
	)
	(label "DA+"
		(at 205.74 53.34 180)
		(effects
			(font
				(size 1.27 1.27)
			)
			(justify right bottom)
		)
	)
	(label "DC_FL+"
		(at 231.14 78.74 180)
		(effects
			(font
				(size 1.27 1.27)
			)
			(justify right bottom)
		)
	)
	(label "GbE.MDI1+"
		(at 281.94 67.31 0)
		(effects
			(font
				(size 1.27 1.27)
			)
			(justify left bottom)
		)
	)
	(label "EN_1B"
		(at 229.87 160.02 180)
		(effects
			(font
				(size 1.27 1.27)
			)
			(justify right bottom)
		)
	)
	(label "P1_VBUS"
		(at 173.99 154.94 180)
		(effects
			(font
				(size 1.27 1.27)
			)
			(justify right bottom)
		)
	)
	(label "GbE.MDI0+"
		(at 281.94 54.61 0)
		(effects
			(font
				(size 1.27 1.27)
			)
			(justify left bottom)
		)
	)
	(label "DA-"
		(at 170.18 66.04 180)
		(effects
			(font
				(size 1.27 1.27)
			)
			(justify right bottom)
		)
	)
	(label "DA-"
		(at 205.74 58.42 180)
		(effects
			(font
				(size 1.27 1.27)
			)
			(justify right bottom)
		)
	)
	(label "DB+"
		(at 205.74 66.04 180)
		(effects
			(font
				(size 1.27 1.27)
			)
			(justify right bottom)
		)
	)
	(label "USBSS_2.RX+"
		(at 217.17 246.38 180)
		(effects
			(font
				(size 1.27 1.27)
			)
			(justify right bottom)
		)
	)
	(label "USB_2.D-"
		(at 255.27 243.84 180)
		(effects
			(font
				(size 1.27 1.27)
			)
			(justify right bottom)
		)
	)
	(label "DD_FL-"
		(at 231.14 96.52 180)
		(effects
			(font
				(size 1.27 1.27)
			)
			(justify right bottom)
		)
	)
	(label "P2_D-"
		(at 173.99 243.84 180)
		(effects
			(font
				(size 1.27 1.27)
			)
			(justify right bottom)
		)
	)
	(label "DB+"
		(at 170.18 68.58 180)
		(effects
			(font
				(size 1.27 1.27)
			)
			(justify right bottom)
		)
	)
	(label "GbE.MDI1-"
		(at 281.94 69.85 0)
		(effects
			(font
				(size 1.27 1.27)
			)
			(justify left bottom)
		)
	)
	(label "DC-"
		(at 170.18 73.66 180)
		(effects
			(font
				(size 1.27 1.27)
			)
			(justify right bottom)
		)
	)
	(label "USBSS_1.RX+"
		(at 217.17 176.53 180)
		(effects
			(font
				(size 1.27 1.27)
			)
			(justify right bottom)
		)
	)
	(hierarchical_label "USBSS_1{USBSS}"
		(shape input)
		(at 269.24 187.96 0)
		(effects
			(font
				(size 1.27 1.27)
			)
			(justify left)
		)
	)
	(hierarchical_label "USB_1{USB}"
		(shape input)
		(at 269.24 168.91 0)
		(effects
			(font
				(size 1.27 1.27)
			)
			(justify left)
		)
	)
	(hierarchical_label "FLG_2"
		(shape output)
		(at 269.24 227.33 0)
		(effects
			(font
				(size 1.27 1.27)
			)
			(justify left)
		)
	)
	(hierarchical_label "~{GBE0_ACT}"
		(shape input)
		(at 82.55 63.5 180)
		(effects
			(font
				(size 1.27 1.27)
			)
			(justify right)
		)
	)
	(hierarchical_label "~{GBE0_LINK_1000}"
		(shape input)
		(at 82.55 83.82 180)
		(effects
			(font
				(size 1.27 1.27)
			)
			(justify right)
		)
	)
	(hierarchical_label "~{GBE0_LINK}"
		(shape input)
		(at 82.55 86.36 180)
		(effects
			(font
				(size 1.27 1.27)
			)
			(justify right)
		)
	)
	(hierarchical_label "GbE{GbE}"
		(shape input)
		(at 299.72 43.18 0)
		(effects
			(font
				(size 1.27 1.27)
			)
			(justify left)
		)
	)
	(hierarchical_label "USB_2{USB}"
		(shape input)
		(at 269.24 238.76 0)
		(effects
			(font
				(size 1.27 1.27)
			)
			(justify left)
		)
	)
	(hierarchical_label "EN_2"
		(shape input)
		(at 269.24 229.87 0)
		(effects
			(font
				(size 1.27 1.27)
			)
			(justify left)
		)
	)
	(hierarchical_label "FLG_1"
		(shape output)
		(at 269.24 157.48 0)
		(effects
			(font
				(size 1.27 1.27)
			)
			(justify left)
		)
	)
	(hierarchical_label "EN_1"
		(shape input)
		(at 269.24 160.02 0)
		(effects
			(font
				(size 1.27 1.27)
			)
			(justify left)
		)
	)
	(hierarchical_label "USBSS_2{USBSS}"
		(shape input)
		(at 269.24 257.81 0)
		(effects
			(font
				(size 1.27 1.27)
			)
			(justify left)
		)
	)
	(symbol
		(lib_id "antmicroTVSDiodes:PESD5Z5_0F")
		(at 182.88 227.33 90)
		(mirror x)
		(unit 1)
		(exclude_from_sim no)
		(in_bom yes)
		(on_board yes)
		(dnp no)
		(fields_autoplaced yes)
		(property "Reference" "D2"
			(at 180.34 228.6 90)
			(effects
				(font
					(size 1.27 1.27)
					(thickness 0.15)
				)
				(justify left)
			)
		)
		(property "Value" "PESD5Z5_0F"
			(at 186.055 230.1875 90)
			(effects
				(font
					(size 1.27 1.27)
					(thickness 0.15)
				)
				(justify right)
				(hide yes)
			)
		)
		(property "Footprint" "antmicro-footprints:SOD-523"
			(at 187.96 242.57 0)
			(effects
				(font
					(size 1.27 1.27)
					(thickness 0.15)
				)
				(justify left bottom)
				(hide yes)
			)
		)
		(property "Datasheet" "https://assets.nexperia.com/documents/data-sheet/PESD5Z5_0.pdf"
			(at 190.5 242.57 0)
			(effects
				(font
					(size 1.27 1.27)
					(thickness 0.15)
				)
				(justify left bottom)
				(hide yes)
			)
		)
		(property "Description" ""
			(at 182.88 227.33 0)
			(effects
				(font
					(size 1.27 1.27)
				)
				(hide yes)
			)
		)
		(property "Manufacturer" "Nexperia"
			(at 193.04 242.57 0)
			(effects
				(font
					(size 1.27 1.27)
					(thickness 0.15)
				)
				(justify left bottom)
				(hide yes)
			)
		)
		(property "MPN" "PESD5Z5.0F"
			(at 180.34 231.14 90)
			(effects
				(font
					(size 1.27 1.27)
					(thickness 0.15)
				)
				(justify left)
			)
		)
		(property "Author" "Antmicro"
			(at 198.12 242.57 0)
			(effects
				(font
					(size 1.27 1.27)
					(thickness 0.15)
				)
				(justify left bottom)
				(hide yes)
			)
		)
		(property "License" "Apache-2.0"
			(at 200.66 242.57 0)
			(effects
				(font
					(size 1.27 1.27)
					(thickness 0.15)
				)
				(justify left bottom)
				(hide yes)
			)
		)
		(property "Public" "False"
			(at 200.66 247.65 0)
			(effects
				(font
					(size 1.27 1.27)
				)
				(justify left bottom)
				(hide yes)
			)
		)
		(pin "2"
		)
		(pin "1"
		)
		(instances
			(project "com-express-7-baseboard"
				(path ""
					(reference "D2")
					(unit 1)
				)
			)
		)
	)
	(symbol
		(lib_id "antmicroResistors0402:R_0R_0402")
		(at 93.98 86.36 0)
		(unit 1)
		(exclude_from_sim no)
		(in_bom yes)
		(on_board yes)
		(dnp yes)
		(property "Reference" "R4"
			(at 92.71 85.09 0)
			(effects
				(font
					(size 1.27 1.27)
					(thickness 0.15)
				)
			)
		)
		(property "Value" "R_0R_0402"
			(at 114.3 99.06 0)
			(effects
				(font
					(size 1.27 1.27)
					(thickness 0.15)
				)
				(justify left bottom)
				(hide yes)
			)
		)
		(property "Footprint" "antmicro-footprints:R_0402_1005Metric"
			(at 114.3 101.6 0)
			(effects
				(font
					(size 1.27 1.27)
					(thickness 0.15)
				)
				(justify left bottom)
				(hide yes)
			)
		)
		(property "Datasheet" "https://industrial.panasonic.com/cdbs/www-data/pdf/RDA0000/AOA0000C301.pdf"
			(at 114.3 104.14 0)
			(effects
				(font
					(size 1.27 1.27)
					(thickness 0.15)
				)
				(justify left bottom)
				(hide yes)
			)
		)
		(property "Description" ""
			(at 93.98 86.36 0)
			(effects
				(font
					(size 1.27 1.27)
				)
				(hide yes)
			)
		)
		(property "MPN" "ERJ2GE0R00X"
			(at 114.3 106.68 0)
			(effects
				(font
					(size 1.27 1.27)
					(thickness 0.15)
				)
				(justify left bottom)
				(hide yes)
			)
		)
		(property "Manufacturer" "Panasonic"
			(at 114.3 109.22 0)
			(effects
				(font
					(size 1.27 1.27)
					(thickness 0.15)
				)
				(justify left bottom)
				(hide yes)
			)
		)
		(property "License" "Apache-2.0"
			(at 114.3 111.76 0)
			(effects
				(font
					(size 1.27 1.27)
					(thickness 0.15)
				)
				(justify left bottom)
				(hide yes)
			)
		)
		(property "Author" "Antmicro"
			(at 114.3 114.3 0)
			(effects
				(font
					(size 1.27 1.27)
					(thickness 0.15)
				)
				(justify left bottom)
				(hide yes)
			)
		)
		(property "Val" "0R"
			(at 100.33 85.09 0)
			(effects
				(font
					(size 1.27 1.27)
					(thickness 0.15)
				)
			)
		)
		(property "Tolerance" "~"
			(at 114.3 96.52 0)
			(effects
				(font
					(size 1.27 1.27)
				)
				(justify left bottom)
				(hide yes)
			)
		)
		(property "Current" "1A"
			(at 114.3 116.84 0)
			(effects
				(font
					(size 1.27 1.27)
					(thickness 0.15)
				)
				(justify left bottom)
				(hide yes)
			)
		)
		(property "Public" "False"
			(at 114.3 116.84 0)
			(effects
				(font
					(size 1.27 1.27)
				)
				(justify left bottom)
				(hide yes)
			)
		)
		(pin "1"
		)
		(pin "2"
		)
		(instances
			(project "com-express-7-baseboard"
				(path ""
					(reference "R4")
					(unit 1)
				)
			)
		)
	)
	(symbol
		(lib_id "antmicroCapacitors0402:C_100n_0402")
		(at 267.97 100.33 270)
		(unit 1)
		(exclude_from_sim no)
		(in_bom yes)
		(on_board yes)
		(dnp no)
		(property "Reference" "C14"
			(at 268.605 100.965 90)
			(effects
				(font
					(size 1.27 1.27)
					(thickness 0.15)
				)
				(justify left)
			)
		)
		(property "Value" "C_100n_0402"
			(at 257.81 120.65 0)
			(effects
				(font
					(size 1.27 1.27)
					(thickness 0.15)
				)
				(justify left bottom)
				(hide yes)
			)
		)
		(property "Footprint" "antmicro-footprints:C_0402_1005Metric"
			(at 255.27 120.65 0)
			(effects
				(font
					(size 1.27 1.27)
					(thickness 0.15)
				)
				(justify left bottom)
				(hide yes)
			)
		)
		(property "Datasheet" "https://www.murata.com/products/productdetail?partno=GRM155R61H104KE14%23"
			(at 252.73 120.65 0)
			(effects
				(font
					(size 1.27 1.27)
					(thickness 0.15)
				)
				(justify left bottom)
				(hide yes)
			)
		)
		(property "Description" ""
			(at 267.97 100.33 0)
			(effects
				(font
					(size 1.27 1.27)
				)
				(hide yes)
			)
		)
		(property "MPN" "GRM155R61H104KE14D"
			(at 250.19 120.65 0)
			(effects
				(font
					(size 1.27 1.27)
					(thickness 0.15)
				)
				(justify left bottom)
				(hide yes)
			)
		)
		(property "Manufacturer" "Murata"
			(at 247.65 120.65 0)
			(effects
				(font
					(size 1.27 1.27)
					(thickness 0.15)
				)
				(justify left bottom)
				(hide yes)
			)
		)
		(property "License" "Apache-2.0"
			(at 245.11 120.65 0)
			(effects
				(font
					(size 1.27 1.27)
					(thickness 0.15)
				)
				(justify left bottom)
				(hide yes)
			)
		)
		(property "Author" "Antmicro"
			(at 242.57 120.65 0)
			(effects
				(font
					(size 1.27 1.27)
					(thickness 0.15)
				)
				(justify left bottom)
				(hide yes)
			)
		)
		(property "Val" "100n"
			(at 268.605 104.775 90)
			(effects
				(font
					(size 1.27 1.27)
					(thickness 0.15)
				)
				(justify left)
			)
		)
		(property "Voltage" "50V"
			(at 240.03 120.65 0)
			(effects
				(font
					(size 1.27 1.27)
				)
				(justify left bottom)
				(hide yes)
			)
		)
		(property "Dielectric" "X5R"
			(at 237.49 120.65 0)
			(effects
				(font
					(size 1.27 1.27)
				)
				(justify left bottom)
				(hide yes)
			)
		)
		(property "Public" "False"
			(at 234.95 120.65 0)
			(effects
				(font
					(size 1.27 1.27)
				)
				(justify left bottom)
				(hide yes)
			)
		)
		(pin "2"
		)
		(pin "1"
		)
		(instances
			(project "com-express-7-baseboard"
				(path ""
					(reference "C14")
					(unit 1)
				)
			)
		)
	)
	(symbol
		(lib_id "antmicroCapacitors0402:C_1u_0402")
		(at 149.86 162.56 270)
		(mirror x)
		(unit 1)
		(exclude_from_sim no)
		(in_bom yes)
		(on_board yes)
		(dnp no)
		(property "Reference" "C1"
			(at 147.32 158.7435 90)
			(effects
				(font
					(size 1.27 1.27)
					(thickness 0.15)
				)
				(justify right)
			)
		)
		(property "Value" "C_1u_0402"
			(at 139.7 142.24 0)
			(effects
				(font
					(size 1.27 1.27)
					(thickness 0.15)
				)
				(justify left bottom)
				(hide yes)
			)
		)
		(property "Footprint" "antmicro-footprints:C_0402_1005Metric"
			(at 137.16 142.24 0)
			(effects
				(font
					(size 1.27 1.27)
					(thickness 0.15)
				)
				(justify left bottom)
				(hide yes)
			)
		)
		(property "Datasheet" "https://product.tdk.com/en/search/capacitor/ceramic/mlcc/info?part_no=C1005X6S1A105K050BC"
			(at 134.62 142.24 0)
			(effects
				(font
					(size 1.27 1.27)
					(thickness 0.15)
				)
				(justify left bottom)
				(hide yes)
			)
		)
		(property "Description" ""
			(at 149.86 162.56 0)
			(effects
				(font
					(size 1.27 1.27)
				)
				(hide yes)
			)
		)
		(property "MPN" "C1005X6S1A105K050BC"
			(at 132.08 142.24 0)
			(effects
				(font
					(size 1.27 1.27)
					(thickness 0.15)
				)
				(justify left bottom)
				(hide yes)
			)
		)
		(property "Manufacturer" "TDK"
			(at 129.54 142.24 0)
			(effects
				(font
					(size 1.27 1.27)
					(thickness 0.15)
				)
				(justify left bottom)
				(hide yes)
			)
		)
		(property "License" "Apache-2.0"
			(at 127 142.24 0)
			(effects
				(font
					(size 1.27 1.27)
					(thickness 0.15)
				)
				(justify left bottom)
				(hide yes)
			)
		)
		(property "Author" "Antmicro"
			(at 124.46 142.24 0)
			(effects
				(font
					(size 1.27 1.27)
					(thickness 0.15)
				)
				(justify left bottom)
				(hide yes)
			)
		)
		(property "Val" "1u"
			(at 147.32 161.2835 90)
			(effects
				(font
					(size 1.27 1.27)
					(thickness 0.15)
				)
				(justify right)
			)
		)
		(property "Voltage" ""
			(at 121.92 142.24 0)
			(effects
				(font
					(size 1.27 1.27)
				)
				(justify left bottom)
				(hide yes)
			)
		)
		(property "Dielectric" ""
			(at 119.38 142.24 0)
			(effects
				(font
					(size 1.27 1.27)
				)
				(justify left bottom)
				(hide yes)
			)
		)
		(property "Public" "False"
			(at 116.84 142.24 0)
			(effects
				(font
					(size 1.27 1.27)
				)
				(justify left bottom)
				(hide yes)
			)
		)
		(pin "1"
		)
		(pin "2"
		)
		(instances
			(project "com-express-7-baseboard"
				(path ""
					(reference "C1")
					(unit 1)
				)
			)
		)
	)
	(symbol
		(lib_id "antmicropower:GND")
		(at 267.97 106.68 0)
		(mirror y)
		(unit 1)
		(exclude_from_sim no)
		(in_bom yes)
		(on_board yes)
		(dnp no)
		(property "Reference" "#PWR026"
			(at 259.08 109.22 0)
			(effects
				(font
					(size 1.27 1.27)
					(thickness 0.15)
				)
				(justify left bottom)
				(hide yes)
			)
		)
		(property "Value" "GND"
			(at 267.97 110.49 0)
			(effects
				(font
					(size 1.27 1.27)
					(thickness 0.15)
				)
			)
		)
		(property "Footprint" ""
			(at 259.08 114.3 0)
			(effects
				(font
					(size 1.27 1.27)
					(thickness 0.15)
				)
				(justify left bottom)
				(hide yes)
			)
		)
		(property "Datasheet" ""
			(at 259.08 119.38 0)
			(effects
				(font
					(size 1.27 1.27)
					(thickness 0.15)
				)
				(justify left bottom)
				(hide yes)
			)
		)
		(property "Description" ""
			(at 267.97 106.68 0)
			(effects
				(font
					(size 1.27 1.27)
				)
				(hide yes)
			)
		)
		(property "Author" "Antmicro"
			(at 259.08 114.3 0)
			(effects
				(font
					(size 1.27 1.27)
					(thickness 0.15)
				)
				(justify left bottom)
				(hide yes)
			)
		)
		(property "License" "Apache-2.0"
			(at 259.08 116.84 0)
			(effects
				(font
					(size 1.27 1.27)
					(thickness 0.15)
				)
				(justify left bottom)
				(hide yes)
			)
		)
		(pin "1"
		)
		(instances
			(project "com-express-7-baseboard"
				(path ""
					(reference "#PWR026")
					(unit 1)
				)
			)
		)
	)
	(symbol
		(lib_id "antmicroResistors0402:R_0R_0402")
		(at 238.76 173.99 0)
		(mirror y)
		(unit 1)
		(exclude_from_sim no)
		(in_bom yes)
		(on_board yes)
		(dnp no)
		(property "Reference" "R21"
			(at 232.41 172.72 0)
			(effects
				(font
					(size 1.27 1.27)
					(thickness 0.15)
				)
			)
		)
		(property "Value" "R_0R_0402"
			(at 218.44 186.69 0)
			(effects
				(font
					(size 1.27 1.27)
					(thickness 0.15)
				)
				(justify left bottom)
				(hide yes)
			)
		)
		(property "Footprint" "antmicro-footprints:R_0402_1005Metric"
			(at 218.44 189.23 0)
			(effects
				(font
					(size 1.27 1.27)
					(thickness 0.15)
				)
				(justify left bottom)
				(hide yes)
			)
		)
		(property "Datasheet" "https://industrial.panasonic.com/cdbs/www-data/pdf/RDA0000/AOA0000C301.pdf"
			(at 218.44 191.77 0)
			(effects
				(font
					(size 1.27 1.27)
					(thickness 0.15)
				)
				(justify left bottom)
				(hide yes)
			)
		)
		(property "Description" ""
			(at 238.76 173.99 0)
			(effects
				(font
					(size 1.27 1.27)
				)
				(hide yes)
			)
		)
		(property "MPN" "ERJ2GE0R00X"
			(at 218.44 194.31 0)
			(effects
				(font
					(size 1.27 1.27)
					(thickness 0.15)
				)
				(justify left bottom)
				(hide yes)
			)
		)
		(property "Manufacturer" "Panasonic"
			(at 218.44 196.85 0)
			(effects
				(font
					(size 1.27 1.27)
					(thickness 0.15)
				)
				(justify left bottom)
				(hide yes)
			)
		)
		(property "License" "Apache-2.0"
			(at 218.44 199.39 0)
			(effects
				(font
					(size 1.27 1.27)
					(thickness 0.15)
				)
				(justify left bottom)
				(hide yes)
			)
		)
		(property "Author" "Antmicro"
			(at 218.44 201.93 0)
			(effects
				(font
					(size 1.27 1.27)
					(thickness 0.15)
				)
				(justify left bottom)
				(hide yes)
			)
		)
		(property "Val" "0R"
			(at 240.03 172.72 0)
			(effects
				(font
					(size 1.27 1.27)
					(thickness 0.15)
				)
			)
		)
		(property "Tolerance" "~"
			(at 218.44 184.15 0)
			(effects
				(font
					(size 1.27 1.27)
				)
				(justify left bottom)
				(hide yes)
			)
		)
		(property "Current" "1A"
			(at 218.44 204.47 0)
			(effects
				(font
					(size 1.27 1.27)
					(thickness 0.15)
				)
				(justify left bottom)
				(hide yes)
			)
		)
		(property "Public" "False"
			(at 218.44 204.47 0)
			(effects
				(font
					(size 1.27 1.27)
				)
				(justify left bottom)
				(hide yes)
			)
		)
		(pin "1"
		)
		(pin "2"
		)
		(instances
			(project "com-express-7-baseboard"
				(path ""
					(reference "R21")
					(unit 1)
				)
			)
		)
	)
	(symbol
		(lib_id "antmicropower:GND")
		(at 237.49 245.11 0)
		(mirror y)
		(unit 1)
		(exclude_from_sim no)
		(in_bom yes)
		(on_board yes)
		(dnp no)
		(property "Reference" "#PWR022"
			(at 228.6 247.65 0)
			(effects
				(font
					(size 1.27 1.27)
					(thickness 0.15)
				)
				(justify left bottom)
				(hide yes)
			)
		)
		(property "Value" "GND"
			(at 237.49 248.92 0)
			(effects
				(font
					(size 1.27 1.27)
					(thickness 0.15)
				)
			)
		)
		(property "Footprint" ""
			(at 228.6 252.73 0)
			(effects
				(font
					(size 1.27 1.27)
					(thickness 0.15)
				)
				(justify left bottom)
				(hide yes)
			)
		)
		(property "Datasheet" ""
			(at 228.6 257.81 0)
			(effects
				(font
					(size 1.27 1.27)
					(thickness 0.15)
				)
				(justify left bottom)
				(hide yes)
			)
		)
		(property "Description" ""
			(at 237.49 245.11 0)
			(effects
				(font
					(size 1.27 1.27)
				)
				(hide yes)
			)
		)
		(property "Author" "Antmicro"
			(at 228.6 252.73 0)
			(effects
				(font
					(size 1.27 1.27)
					(thickness 0.15)
				)
				(justify left bottom)
				(hide yes)
			)
		)
		(property "License" "Apache-2.0"
			(at 228.6 255.27 0)
			(effects
				(font
					(size 1.27 1.27)
					(thickness 0.15)
				)
				(justify left bottom)
				(hide yes)
			)
		)
		(pin "1"
		)
		(instances
			(project "com-express-7-baseboard"
				(path ""
					(reference "#PWR022")
					(unit 1)
				)
			)
		)
	)
	(symbol
		(lib_id "antmicroResistors0402:R_10k_0402")
		(at 233.68 156.21 270)
		(mirror x)
		(unit 1)
		(exclude_from_sim no)
		(in_bom yes)
		(on_board yes)
		(dnp yes)
		(property "Reference" "R18"
			(at 232.41 152.4 90)
			(effects
				(font
					(size 1.27 1.27)
					(thickness 0.15)
				)
				(justify right)
			)
		)
		(property "Value" "R_10k_0402"
			(at 220.98 135.89 0)
			(effects
				(font
					(size 1.27 1.27)
					(thickness 0.15)
				)
				(justify left bottom)
				(hide yes)
			)
		)
		(property "Footprint" "antmicro-footprints:R_0402_1005Metric"
			(at 218.44 135.89 0)
			(effects
				(font
					(size 1.27 1.27)
					(thickness 0.15)
				)
				(justify left bottom)
				(hide yes)
			)
		)
		(property "Datasheet" "https://www.bourns.com/docs/product-datasheets/cr.pdf"
			(at 215.9 135.89 0)
			(effects
				(font
					(size 1.27 1.27)
					(thickness 0.15)
				)
				(justify left bottom)
				(hide yes)
			)
		)
		(property "Description" ""
			(at 233.68 156.21 0)
			(effects
				(font
					(size 1.27 1.27)
				)
				(hide yes)
			)
		)
		(property "MPN" "CR0402-FX-1002GLF"
			(at 213.36 135.89 0)
			(effects
				(font
					(size 1.27 1.27)
					(thickness 0.15)
				)
				(justify left bottom)
				(hide yes)
			)
		)
		(property "Manufacturer" "Bourns"
			(at 210.82 135.89 0)
			(effects
				(font
					(size 1.27 1.27)
					(thickness 0.15)
				)
				(justify left bottom)
				(hide yes)
			)
		)
		(property "License" "Apache-2.0"
			(at 208.28 135.89 0)
			(effects
				(font
					(size 1.27 1.27)
					(thickness 0.15)
				)
				(justify left bottom)
				(hide yes)
			)
		)
		(property "Author" "Antmicro"
			(at 205.74 135.89 0)
			(effects
				(font
					(size 1.27 1.27)
					(thickness 0.15)
				)
				(justify left bottom)
				(hide yes)
			)
		)
		(property "Val" "10k"
			(at 232.41 154.94 90)
			(effects
				(font
					(size 1.27 1.27)
					(thickness 0.15)
				)
				(justify right)
			)
		)
		(property "Tolerance" "1%"
			(at 223.52 135.89 0)
			(effects
				(font
					(size 1.27 1.27)
				)
				(justify left bottom)
				(hide yes)
			)
		)
		(property "Public" "False"
			(at 203.2 135.89 0)
			(effects
				(font
					(size 1.27 1.27)
				)
				(justify left bottom)
				(hide yes)
			)
		)
		(pin "1"
		)
		(pin "2"
		)
		(instances
			(project "com-express-7-baseboard"
				(path ""
					(reference "R18")
					(unit 1)
				)
			)
		)
	)
	(symbol
		(lib_id "antmicroResistors0402:R_0R_0402")
		(at 254 160.02 0)
		(mirror y)
		(unit 1)
		(exclude_from_sim no)
		(in_bom yes)
		(on_board yes)
		(dnp no)
		(property "Reference" "R27"
			(at 256.54 158.75 0)
			(effects
				(font
					(size 1.27 1.27)
					(thickness 0.15)
				)
			)
		)
		(property "Value" "R_0R_0402"
			(at 233.68 172.72 0)
			(effects
				(font
					(size 1.27 1.27)
					(thickness 0.15)
				)
				(justify left bottom)
				(hide yes)
			)
		)
		(property "Footprint" "antmicro-footprints:R_0402_1005Metric"
			(at 233.68 175.26 0)
			(effects
				(font
					(size 1.27 1.27)
					(thickness 0.15)
				)
				(justify left bottom)
				(hide yes)
			)
		)
		(property "Datasheet" "https://industrial.panasonic.com/cdbs/www-data/pdf/RDA0000/AOA0000C301.pdf"
			(at 233.68 177.8 0)
			(effects
				(font
					(size 1.27 1.27)
					(thickness 0.15)
				)
				(justify left bottom)
				(hide yes)
			)
		)
		(property "Description" ""
			(at 254 160.02 0)
			(effects
				(font
					(size 1.27 1.27)
				)
				(hide yes)
			)
		)
		(property "MPN" "ERJ2GE0R00X"
			(at 233.68 180.34 0)
			(effects
				(font
					(size 1.27 1.27)
					(thickness 0.15)
				)
				(justify left bottom)
				(hide yes)
			)
		)
		(property "Manufacturer" "Panasonic"
			(at 233.68 182.88 0)
			(effects
				(font
					(size 1.27 1.27)
					(thickness 0.15)
				)
				(justify left bottom)
				(hide yes)
			)
		)
		(property "License" "Apache-2.0"
			(at 233.68 185.42 0)
			(effects
				(font
					(size 1.27 1.27)
					(thickness 0.15)
				)
				(justify left bottom)
				(hide yes)
			)
		)
		(property "Author" "Antmicro"
			(at 233.68 187.96 0)
			(effects
				(font
					(size 1.27 1.27)
					(thickness 0.15)
				)
				(justify left bottom)
				(hide yes)
			)
		)
		(property "Val" "0R"
			(at 247.65 158.75 0)
			(effects
				(font
					(size 1.27 1.27)
					(thickness 0.15)
				)
			)
		)
		(property "Tolerance" "~"
			(at 233.68 170.18 0)
			(effects
				(font
					(size 1.27 1.27)
				)
				(justify left bottom)
				(hide yes)
			)
		)
		(property "Current" "1A"
			(at 233.68 190.5 0)
			(effects
				(font
					(size 1.27 1.27)
					(thickness 0.15)
				)
				(justify left bottom)
				(hide yes)
			)
		)
		(property "Public" "False"
			(at 233.68 190.5 0)
			(effects
				(font
					(size 1.27 1.27)
				)
				(justify left bottom)
				(hide yes)
			)
		)
		(pin "1"
		)
		(pin "2"
		)
		(instances
			(project "com-express-7-baseboard"
				(path ""
					(reference "R27")
					(unit 1)
				)
			)
		)
	)
	(symbol
		(lib_id "antmicroResistors0402:R_470R_0402")
		(at 134.62 59.69 90)
		(unit 1)
		(exclude_from_sim no)
		(in_bom yes)
		(on_board yes)
		(dnp yes)
		(property "Reference" "R9"
			(at 135.89 55.88 90)
			(effects
				(font
					(size 1.27 1.27)
					(thickness 0.15)
				)
				(justify right)
			)
		)
		(property "Value" "R_470R_0402"
			(at 147.32 39.37 0)
			(effects
				(font
					(size 1.27 1.27)
					(thickness 0.15)
				)
				(justify left bottom)
				(hide yes)
			)
		)
		(property "Footprint" "antmicro-footprints:R_0402_1005Metric"
			(at 149.86 39.37 0)
			(effects
				(font
					(size 1.27 1.27)
					(thickness 0.15)
				)
				(justify left bottom)
				(hide yes)
			)
		)
		(property "Datasheet" "https://www.bourns.com/docs/product-datasheets/cr.pdf"
			(at 152.4 39.37 0)
			(effects
				(font
					(size 1.27 1.27)
					(thickness 0.15)
				)
				(justify left bottom)
				(hide yes)
			)
		)
		(property "Description" ""
			(at 134.62 59.69 0)
			(effects
				(font
					(size 1.27 1.27)
				)
				(hide yes)
			)
		)
		(property "MPN" "CR0402-FX-4700GLF"
			(at 154.94 39.37 0)
			(effects
				(font
					(size 1.27 1.27)
					(thickness 0.15)
				)
				(justify left bottom)
				(hide yes)
			)
		)
		(property "Manufacturer" "Bourns"
			(at 157.48 39.37 0)
			(effects
				(font
					(size 1.27 1.27)
					(thickness 0.15)
				)
				(justify left bottom)
				(hide yes)
			)
		)
		(property "License" "Apache-2.0"
			(at 160.02 39.37 0)
			(effects
				(font
					(size 1.27 1.27)
					(thickness 0.15)
				)
				(justify left bottom)
				(hide yes)
			)
		)
		(property "Author" "Antmicro"
			(at 162.56 39.37 0)
			(effects
				(font
					(size 1.27 1.27)
					(thickness 0.15)
				)
				(justify left bottom)
				(hide yes)
			)
		)
		(property "Val" "470R"
			(at 135.89 58.42 90)
			(effects
				(font
					(size 1.27 1.27)
					(thickness 0.15)
				)
				(justify right)
			)
		)
		(property "Tolerance" "1%"
			(at 144.78 39.37 0)
			(effects
				(font
					(size 1.27 1.27)
				)
				(justify left bottom)
				(hide yes)
			)
		)
		(property "Public" "False"
			(at 165.1 39.37 0)
			(effects
				(font
					(size 1.27 1.27)
				)
				(justify left bottom)
				(hide yes)
			)
		)
		(pin "2"
		)
		(pin "1"
		)
		(instances
			(project "com-express-7-baseboard"
				(path ""
					(reference "R9")
					(unit 1)
				)
			)
		)
	)
	(symbol
		(lib_id "antmicroResistors0402:R_0R_0402")
		(at 93.98 92.71 0)
		(unit 1)
		(exclude_from_sim no)
		(in_bom yes)
		(on_board yes)
		(dnp yes)
		(property "Reference" "R6"
			(at 92.71 93.98 0)
			(effects
				(font
					(size 1.27 1.27)
					(thickness 0.15)
				)
			)
		)
		(property "Value" "R_0R_0402"
			(at 114.3 105.41 0)
			(effects
				(font
					(size 1.27 1.27)
					(thickness 0.15)
				)
				(justify left bottom)
				(hide yes)
			)
		)
		(property "Footprint" "antmicro-footprints:R_0402_1005Metric"
			(at 114.3 107.95 0)
			(effects
				(font
					(size 1.27 1.27)
					(thickness 0.15)
				)
				(justify left bottom)
				(hide yes)
			)
		)
		(property "Datasheet" "https://industrial.panasonic.com/cdbs/www-data/pdf/RDA0000/AOA0000C301.pdf"
			(at 114.3 110.49 0)
			(effects
				(font
					(size 1.27 1.27)
					(thickness 0.15)
				)
				(justify left bottom)
				(hide yes)
			)
		)
		(property "Description" ""
			(at 93.98 92.71 0)
			(effects
				(font
					(size 1.27 1.27)
				)
				(hide yes)
			)
		)
		(property "MPN" "ERJ2GE0R00X"
			(at 114.3 113.03 0)
			(effects
				(font
					(size 1.27 1.27)
					(thickness 0.15)
				)
				(justify left bottom)
				(hide yes)
			)
		)
		(property "Manufacturer" "Panasonic"
			(at 114.3 115.57 0)
			(effects
				(font
					(size 1.27 1.27)
					(thickness 0.15)
				)
				(justify left bottom)
				(hide yes)
			)
		)
		(property "License" "Apache-2.0"
			(at 114.3 118.11 0)
			(effects
				(font
					(size 1.27 1.27)
					(thickness 0.15)
				)
				(justify left bottom)
				(hide yes)
			)
		)
		(property "Author" "Antmicro"
			(at 114.3 120.65 0)
			(effects
				(font
					(size 1.27 1.27)
					(thickness 0.15)
				)
				(justify left bottom)
				(hide yes)
			)
		)
		(property "Val" "0R"
			(at 100.33 93.98 0)
			(effects
				(font
					(size 1.27 1.27)
					(thickness 0.15)
				)
			)
		)
		(property "Tolerance" "~"
			(at 114.3 102.87 0)
			(effects
				(font
					(size 1.27 1.27)
				)
				(justify left bottom)
				(hide yes)
			)
		)
		(property "Current" "1A"
			(at 114.3 123.19 0)
			(effects
				(font
					(size 1.27 1.27)
					(thickness 0.15)
				)
				(justify left bottom)
				(hide yes)
			)
		)
		(property "Public" "False"
			(at 114.3 123.19 0)
			(effects
				(font
					(size 1.27 1.27)
				)
				(justify left bottom)
				(hide yes)
			)
		)
		(pin "1"
		)
		(pin "2"
		)
		(instances
			(project "com-express-7-baseboard"
				(path ""
					(reference "R6")
					(unit 1)
				)
			)
		)
	)
	(symbol
		(lib_id "antmicropower:GND")
		(at 270.51 149.86 0)
		(mirror y)
		(unit 1)
		(exclude_from_sim no)
		(in_bom yes)
		(on_board yes)
		(dnp no)
		(property "Reference" "#PWR028"
			(at 261.62 152.4 0)
			(effects
				(font
					(size 1.27 1.27)
					(thickness 0.15)
				)
				(justify left bottom)
				(hide yes)
			)
		)
		(property "Value" "GND"
			(at 270.51 153.67 0)
			(effects
				(font
					(size 1.27 1.27)
					(thickness 0.15)
				)
			)
		)
		(property "Footprint" ""
			(at 261.62 157.48 0)
			(effects
				(font
					(size 1.27 1.27)
					(thickness 0.15)
				)
				(justify left bottom)
				(hide yes)
			)
		)
		(property "Datasheet" ""
			(at 261.62 162.56 0)
			(effects
				(font
					(size 1.27 1.27)
					(thickness 0.15)
				)
				(justify left bottom)
				(hide yes)
			)
		)
		(property "Description" ""
			(at 270.51 149.86 0)
			(effects
				(font
					(size 1.27 1.27)
				)
				(hide yes)
			)
		)
		(property "Author" "Antmicro"
			(at 261.62 157.48 0)
			(effects
				(font
					(size 1.27 1.27)
					(thickness 0.15)
				)
				(justify left bottom)
				(hide yes)
			)
		)
		(property "License" "Apache-2.0"
			(at 261.62 160.02 0)
			(effects
				(font
					(size 1.27 1.27)
					(thickness 0.15)
				)
				(justify left bottom)
				(hide yes)
			)
		)
		(pin "1"
		)
		(instances
			(project "com-express-7-baseboard"
				(path ""
					(reference "#PWR028")
					(unit 1)
				)
			)
		)
	)
	(symbol
		(lib_id "antmicroTVSDiodes:PESD5Z5_0F")
		(at 182.88 158.75 90)
		(mirror x)
		(unit 1)
		(exclude_from_sim no)
		(in_bom yes)
		(on_board yes)
		(dnp no)
		(fields_autoplaced yes)
		(property "Reference" "D1"
			(at 180.34 160.02 90)
			(effects
				(font
					(size 1.27 1.27)
					(thickness 0.15)
				)
				(justify left)
			)
		)
		(property "Value" "PESD5Z5_0F"
			(at 186.055 161.6075 90)
			(effects
				(font
					(size 1.27 1.27)
					(thickness 0.15)
				)
				(justify right)
				(hide yes)
			)
		)
		(property "Footprint" "antmicro-footprints:SOD-523"
			(at 187.96 173.99 0)
			(effects
				(font
					(size 1.27 1.27)
					(thickness 0.15)
				)
				(justify left bottom)
				(hide yes)
			)
		)
		(property "Datasheet" "https://assets.nexperia.com/documents/data-sheet/PESD5Z5_0.pdf"
			(at 190.5 173.99 0)
			(effects
				(font
					(size 1.27 1.27)
					(thickness 0.15)
				)
				(justify left bottom)
				(hide yes)
			)
		)
		(property "Description" ""
			(at 182.88 158.75 0)
			(effects
				(font
					(size 1.27 1.27)
				)
				(hide yes)
			)
		)
		(property "Manufacturer" "Nexperia"
			(at 193.04 173.99 0)
			(effects
				(font
					(size 1.27 1.27)
					(thickness 0.15)
				)
				(justify left bottom)
				(hide yes)
			)
		)
		(property "MPN" "PESD5Z5.0F"
			(at 180.34 162.56 90)
			(effects
				(font
					(size 1.27 1.27)
					(thickness 0.15)
				)
				(justify left)
			)
		)
		(property "Author" "Antmicro"
			(at 198.12 173.99 0)
			(effects
				(font
					(size 1.27 1.27)
					(thickness 0.15)
				)
				(justify left bottom)
				(hide yes)
			)
		)
		(property "License" "Apache-2.0"
			(at 200.66 173.99 0)
			(effects
				(font
					(size 1.27 1.27)
					(thickness 0.15)
				)
				(justify left bottom)
				(hide yes)
			)
		)
		(property "Public" "False"
			(at 200.66 179.07 0)
			(effects
				(font
					(size 1.27 1.27)
				)
				(justify left bottom)
				(hide yes)
			)
		)
		(pin "2"
		)
		(pin "1"
		)
		(instances
			(project "com-express-7-baseboard"
				(path ""
					(reference "D1")
					(unit 1)
				)
			)
		)
	)
	(symbol
		(lib_id "antmicropower:GND")
		(at 187.96 260.35 0)
		(mirror y)
		(unit 1)
		(exclude_from_sim no)
		(in_bom yes)
		(on_board yes)
		(dnp no)
		(property "Reference" "#PWR013"
			(at 179.07 262.89 0)
			(effects
				(font
					(size 1.27 1.27)
					(thickness 0.15)
				)
				(justify left bottom)
				(hide yes)
			)
		)
		(property "Value" "GND"
			(at 187.96 264.16 0)
			(effects
				(font
					(size 1.27 1.27)
					(thickness 0.15)
				)
			)
		)
		(property "Footprint" ""
			(at 179.07 267.97 0)
			(effects
				(font
					(size 1.27 1.27)
					(thickness 0.15)
				)
				(justify left bottom)
				(hide yes)
			)
		)
		(property "Datasheet" ""
			(at 179.07 273.05 0)
			(effects
				(font
					(size 1.27 1.27)
					(thickness 0.15)
				)
				(justify left bottom)
				(hide yes)
			)
		)
		(property "Description" ""
			(at 187.96 260.35 0)
			(effects
				(font
					(size 1.27 1.27)
				)
				(hide yes)
			)
		)
		(property "Author" "Antmicro"
			(at 179.07 267.97 0)
			(effects
				(font
					(size 1.27 1.27)
					(thickness 0.15)
				)
				(justify left bottom)
				(hide yes)
			)
		)
		(property "License" "Apache-2.0"
			(at 179.07 270.51 0)
			(effects
				(font
					(size 1.27 1.27)
					(thickness 0.15)
				)
				(justify left bottom)
				(hide yes)
			)
		)
		(pin "1"
		)
		(instances
			(project "com-express-7-baseboard"
				(path ""
					(reference "#PWR013")
					(unit 1)
				)
			)
		)
	)
	(symbol
		(lib_id "antmicroCapacitors0402:C_100n_0402")
		(at 261.62 100.33 270)
		(unit 1)
		(exclude_from_sim no)
		(in_bom yes)
		(on_board yes)
		(dnp no)
		(property "Reference" "C13"
			(at 262.255 100.965 90)
			(effects
				(font
					(size 1.27 1.27)
					(thickness 0.15)
				)
				(justify left)
			)
		)
		(property "Value" "C_100n_0402"
			(at 251.46 120.65 0)
			(effects
				(font
					(size 1.27 1.27)
					(thickness 0.15)
				)
				(justify left bottom)
				(hide yes)
			)
		)
		(property "Footprint" "antmicro-footprints:C_0402_1005Metric"
			(at 248.92 120.65 0)
			(effects
				(font
					(size 1.27 1.27)
					(thickness 0.15)
				)
				(justify left bottom)
				(hide yes)
			)
		)
		(property "Datasheet" "https://www.murata.com/products/productdetail?partno=GRM155R61H104KE14%23"
			(at 246.38 120.65 0)
			(effects
				(font
					(size 1.27 1.27)
					(thickness 0.15)
				)
				(justify left bottom)
				(hide yes)
			)
		)
		(property "Description" ""
			(at 261.62 100.33 0)
			(effects
				(font
					(size 1.27 1.27)
				)
				(hide yes)
			)
		)
		(property "MPN" "GRM155R61H104KE14D"
			(at 243.84 120.65 0)
			(effects
				(font
					(size 1.27 1.27)
					(thickness 0.15)
				)
				(justify left bottom)
				(hide yes)
			)
		)
		(property "Manufacturer" "Murata"
			(at 241.3 120.65 0)
			(effects
				(font
					(size 1.27 1.27)
					(thickness 0.15)
				)
				(justify left bottom)
				(hide yes)
			)
		)
		(property "License" "Apache-2.0"
			(at 238.76 120.65 0)
			(effects
				(font
					(size 1.27 1.27)
					(thickness 0.15)
				)
				(justify left bottom)
				(hide yes)
			)
		)
		(property "Author" "Antmicro"
			(at 236.22 120.65 0)
			(effects
				(font
					(size 1.27 1.27)
					(thickness 0.15)
				)
				(justify left bottom)
				(hide yes)
			)
		)
		(property "Val" "100n"
			(at 262.255 104.775 90)
			(effects
				(font
					(size 1.27 1.27)
					(thickness 0.15)
				)
				(justify left)
			)
		)
		(property "Voltage" "50V"
			(at 233.68 120.65 0)
			(effects
				(font
					(size 1.27 1.27)
				)
				(justify left bottom)
				(hide yes)
			)
		)
		(property "Dielectric" "X5R"
			(at 231.14 120.65 0)
			(effects
				(font
					(size 1.27 1.27)
				)
				(justify left bottom)
				(hide yes)
			)
		)
		(property "Public" "False"
			(at 228.6 120.65 0)
			(effects
				(font
					(size 1.27 1.27)
				)
				(justify left bottom)
				(hide yes)
			)
		)
		(pin "2"
		)
		(pin "1"
		)
		(instances
			(project "com-express-7-baseboard"
				(path ""
					(reference "C13")
					(unit 1)
				)
			)
		)
	)
	(symbol
		(lib_id "antmicroResistors0402:R_470R_0402")
		(at 128.27 73.66 90)
		(unit 1)
		(exclude_from_sim no)
		(in_bom yes)
		(on_board yes)
		(dnp no)
		(property "Reference" "R330"
			(at 127 69.85 90)
			(effects
				(font
					(size 1.27 1.27)
					(thickness 0.15)
				)
				(justify left)
			)
		)
		(property "Value" "R_470R_0402"
			(at 140.97 53.34 0)
			(effects
				(font
					(size 1.27 1.27)
					(thickness 0.15)
				)
				(justify left bottom)
				(hide yes)
			)
		)
		(property "Footprint" "antmicro-footprints:R_0402_1005Metric"
			(at 143.51 53.34 0)
			(effects
				(font
					(size 1.27 1.27)
					(thickness 0.15)
				)
				(justify left bottom)
				(hide yes)
			)
		)
		(property "Datasheet" "https://www.bourns.com/docs/product-datasheets/cr.pdf"
			(at 146.05 53.34 0)
			(effects
				(font
					(size 1.27 1.27)
					(thickness 0.15)
				)
				(justify left bottom)
				(hide yes)
			)
		)
		(property "Description" ""
			(at 128.27 73.66 0)
			(effects
				(font
					(size 1.27 1.27)
				)
				(hide yes)
			)
		)
		(property "MPN" "CR0402-FX-4700GLF"
			(at 148.59 53.34 0)
			(effects
				(font
					(size 1.27 1.27)
					(thickness 0.15)
				)
				(justify left bottom)
				(hide yes)
			)
		)
		(property "Manufacturer" "Bourns"
			(at 151.13 53.34 0)
			(effects
				(font
					(size 1.27 1.27)
					(thickness 0.15)
				)
				(justify left bottom)
				(hide yes)
			)
		)
		(property "License" "Apache-2.0"
			(at 153.67 53.34 0)
			(effects
				(font
					(size 1.27 1.27)
					(thickness 0.15)
				)
				(justify left bottom)
				(hide yes)
			)
		)
		(property "Author" "Antmicro"
			(at 156.21 53.34 0)
			(effects
				(font
					(size 1.27 1.27)
					(thickness 0.15)
				)
				(justify left bottom)
				(hide yes)
			)
		)
		(property "Val" "470R"
			(at 127 72.39 90)
			(effects
				(font
					(size 1.27 1.27)
					(thickness 0.15)
				)
				(justify left)
			)
		)
		(property "Tolerance" "1%"
			(at 138.43 53.34 0)
			(effects
				(font
					(size 1.27 1.27)
				)
				(justify left bottom)
				(hide yes)
			)
		)
		(property "Public" "False"
			(at 158.75 53.34 0)
			(effects
				(font
					(size 1.27 1.27)
				)
				(justify left bottom)
				(hide yes)
			)
		)
		(pin "2"
		)
		(pin "1"
		)
		(instances
			(project "com-express-7-baseboard"
				(path ""
					(reference "R330")
					(unit 1)
				)
			)
		)
	)
	(symbol
		(lib_id "antmicroResistors0402:R_2k2_0402")
		(at 204.47 162.56 270)
		(mirror x)
		(unit 1)
		(exclude_from_sim no)
		(in_bom yes)
		(on_board yes)
		(dnp no)
		(property "Reference" "R12"
			(at 199.39 158.75 90)
			(effects
				(font
					(size 1.27 1.27)
				)
				(justify left)
			)
		)
		(property "Value" "R_2k2_0402"
			(at 191.77 142.24 0)
			(effects
				(font
					(size 1.27 1.27)
					(thickness 0.15)
				)
				(justify left bottom)
				(hide yes)
			)
		)
		(property "Footprint" "antmicro-footprints:R_0402_1005Metric"
			(at 189.23 142.24 0)
			(effects
				(font
					(size 1.27 1.27)
					(thickness 0.15)
				)
				(justify left bottom)
				(hide yes)
			)
		)
		(property "Datasheet" "https://www.bourns.com/docs/product-datasheets/cr.pdf"
			(at 186.69 142.24 0)
			(effects
				(font
					(size 1.27 1.27)
					(thickness 0.15)
				)
				(justify left bottom)
				(hide yes)
			)
		)
		(property "Description" ""
			(at 204.47 162.56 0)
			(effects
				(font
					(size 1.27 1.27)
				)
				(hide yes)
			)
		)
		(property "Manufacturer" "Bourns"
			(at 181.61 142.24 0)
			(effects
				(font
					(size 1.27 1.27)
					(thickness 0.15)
				)
				(justify left bottom)
				(hide yes)
			)
		)
		(property "MPN" "CR0402-FX-2201GLF"
			(at 184.15 142.24 0)
			(effects
				(font
					(size 1.27 1.27)
					(thickness 0.15)
				)
				(justify left bottom)
				(hide yes)
			)
		)
		(property "Val" "2k2"
			(at 199.39 161.29 90)
			(effects
				(font
					(size 1.27 1.27)
					(thickness 0.15)
				)
				(justify left)
			)
		)
		(property "License" "Apache-2.0"
			(at 179.07 142.24 0)
			(effects
				(font
					(size 1.27 1.27)
					(thickness 0.15)
				)
				(justify left bottom)
				(hide yes)
			)
		)
		(property "Author" "Antmicro"
			(at 176.53 142.24 0)
			(effects
				(font
					(size 1.27 1.27)
					(thickness 0.15)
				)
				(justify left bottom)
				(hide yes)
			)
		)
		(property "Tolerance" "1%"
			(at 194.31 142.24 0)
			(effects
				(font
					(size 1.27 1.27)
				)
				(justify left bottom)
				(hide yes)
			)
		)
		(property "Public" "False"
			(at 173.99 142.24 0)
			(effects
				(font
					(size 1.27 1.27)
				)
				(justify left bottom)
				(hide yes)
			)
		)
		(pin "1"
		)
		(pin "2"
		)
		(instances
			(project "com-express-7-baseboard"
				(path ""
					(reference "R12")
					(unit 1)
				)
			)
		)
	)
	(symbol
		(lib_id "antmicropower:+3V3")
		(at 110.49 73.66 0)
		(unit 1)
		(exclude_from_sim no)
		(in_bom yes)
		(on_board yes)
		(dnp no)
		(property "Reference" "#PWR02"
			(at 125.73 73.66 0)
			(effects
				(font
					(size 1.27 1.27)
					(thickness 0.15)
				)
				(justify left bottom)
				(hide yes)
			)
		)
		(property "Value" "+3V3"
			(at 110.49 69.85 0)
			(effects
				(font
					(size 1.27 1.27)
					(thickness 0.15)
				)
			)
		)
		(property "Footprint" ""
			(at 125.73 81.28 0)
			(effects
				(font
					(size 1.27 1.27)
					(thickness 0.15)
				)
				(justify left bottom)
				(hide yes)
			)
		)
		(property "Datasheet" ""
			(at 125.73 83.82 0)
			(effects
				(font
					(size 1.27 1.27)
					(thickness 0.15)
				)
				(justify left bottom)
				(hide yes)
			)
		)
		(property "Description" ""
			(at 110.49 73.66 0)
			(effects
				(font
					(size 1.27 1.27)
				)
				(hide yes)
			)
		)
		(property "Author" "Antmicro"
			(at 125.73 76.2 0)
			(effects
				(font
					(size 1.27 1.27)
					(thickness 0.15)
				)
				(justify left bottom)
				(hide yes)
			)
		)
		(property "License" "Apache-2.0"
			(at 125.73 78.74 0)
			(effects
				(font
					(size 1.27 1.27)
					(thickness 0.15)
				)
				(justify left bottom)
				(hide yes)
			)
		)
		(pin "1"
		)
		(instances
			(project "com-express-7-baseboard"
				(path ""
					(reference "#PWR02")
					(unit 1)
				)
			)
		)
	)
	(symbol
		(lib_id "antmicroCommonModeChokes:Choke_SRF2012A-801Y")
		(at 220.98 78.74 0)
		(mirror y)
		(unit 1)
		(exclude_from_sim no)
		(in_bom yes)
		(on_board yes)
		(dnp no)
		(fields_autoplaced yes)
		(property "Reference" "T3"
			(at 216.281 73.66 0)
			(effects
				(font
					(size 1.27 1.27)
					(thickness 0.15)
				)
			)
		)
		(property "Value" "Choke_SRF2012A-801Y"
			(at 205.74 88.9 0)
			(effects
				(font
					(size 1.27 1.27)
					(thickness 0.15)
				)
				(justify left bottom)
				(hide yes)
			)
		)
		(property "Footprint" "antmicro-footprints:Choke_0805_2012Metric"
			(at 194.31 91.44 0)
			(effects
				(font
					(size 1.27 1.27)
					(thickness 0.15)
				)
				(justify left bottom)
				(hide yes)
			)
		)
		(property "Datasheet" "https://www.bourns.com/docs/product-datasheets/srf2012a-801y.pdf"
			(at 205.74 93.98 0)
			(effects
				(font
					(size 1.27 1.27)
					(thickness 0.15)
				)
				(justify left bottom)
				(hide yes)
			)
		)
		(property "Description" ""
			(at 220.98 78.74 0)
			(effects
				(font
					(size 1.27 1.27)
				)
				(hide yes)
			)
		)
		(property "Manufacturer" "Bourns"
			(at 205.74 96.52 0)
			(effects
				(font
					(size 1.27 1.27)
					(thickness 0.15)
				)
				(justify left bottom)
				(hide yes)
			)
		)
		(property "MPN" "SRF2012A-801Y"
			(at 216.281 76.2 0)
			(effects
				(font
					(size 1.27 1.27)
					(thickness 0.15)
				)
			)
		)
		(property "IMax" "0.3 A"
			(at 205.74 99.06 0)
			(effects
				(font
					(size 1.27 1.27)
					(thickness 0.15)
				)
				(justify left bottom)
				(hide yes)
			)
		)
		(property "Author" "Antmicro"
			(at 205.74 101.6 0)
			(effects
				(font
					(size 1.27 1.27)
					(thickness 0.15)
				)
				(justify left bottom)
				(hide yes)
			)
		)
		(property "License" "Apache-2.0"
			(at 205.74 104.14 0)
			(effects
				(font
					(size 1.27 1.27)
					(thickness 0.15)
				)
				(justify left bottom)
				(hide yes)
			)
		)
		(property "Public" "False"
			(at 194.31 111.76 0)
			(effects
				(font
					(size 1.27 1.27)
				)
				(justify left bottom)
				(hide yes)
			)
		)
		(pin "3"
		)
		(pin "4"
		)
		(pin "1"
		)
		(pin "2"
		)
		(instances
			(project "com-express-7-baseboard"
				(path ""
					(reference "T3")
					(unit 1)
				)
			)
		)
	)
	(symbol
		(lib_id "antmicroCapacitors0402:C_1u_0402")
		(at 195.58 162.56 270)
		(mirror x)
		(unit 1)
		(exclude_from_sim no)
		(in_bom yes)
		(on_board yes)
		(dnp no)
		(fields_autoplaced yes)
		(property "Reference" "C8"
			(at 193.04 158.7435 90)
			(effects
				(font
					(size 1.27 1.27)
					(thickness 0.15)
				)
				(justify right)
			)
		)
		(property "Value" "C_1u_0402"
			(at 185.42 142.24 0)
			(effects
				(font
					(size 1.27 1.27)
					(thickness 0.15)
				)
				(justify left bottom)
				(hide yes)
			)
		)
		(property "Footprint" "antmicro-footprints:C_0402_1005Metric"
			(at 182.88 142.24 0)
			(effects
				(font
					(size 1.27 1.27)
					(thickness 0.15)
				)
				(justify left bottom)
				(hide yes)
			)
		)
		(property "Datasheet" "https://product.tdk.com/en/search/capacitor/ceramic/mlcc/info?part_no=C1005X6S1A105K050BC"
			(at 180.34 142.24 0)
			(effects
				(font
					(size 1.27 1.27)
					(thickness 0.15)
				)
				(justify left bottom)
				(hide yes)
			)
		)
		(property "Description" ""
			(at 195.58 162.56 0)
			(effects
				(font
					(size 1.27 1.27)
				)
				(hide yes)
			)
		)
		(property "MPN" "C1005X6S1A105K050BC"
			(at 177.8 142.24 0)
			(effects
				(font
					(size 1.27 1.27)
					(thickness 0.15)
				)
				(justify left bottom)
				(hide yes)
			)
		)
		(property "Manufacturer" "TDK"
			(at 175.26 142.24 0)
			(effects
				(font
					(size 1.27 1.27)
					(thickness 0.15)
				)
				(justify left bottom)
				(hide yes)
			)
		)
		(property "License" "Apache-2.0"
			(at 172.72 142.24 0)
			(effects
				(font
					(size 1.27 1.27)
					(thickness 0.15)
				)
				(justify left bottom)
				(hide yes)
			)
		)
		(property "Author" "Antmicro"
			(at 170.18 142.24 0)
			(effects
				(font
					(size 1.27 1.27)
					(thickness 0.15)
				)
				(justify left bottom)
				(hide yes)
			)
		)
		(property "Val" "1u"
			(at 193.04 161.2835 90)
			(effects
				(font
					(size 1.27 1.27)
					(thickness 0.15)
				)
				(justify right)
			)
		)
		(property "Voltage" ""
			(at 167.64 142.24 0)
			(effects
				(font
					(size 1.27 1.27)
				)
				(justify left bottom)
				(hide yes)
			)
		)
		(property "Dielectric" ""
			(at 165.1 142.24 0)
			(effects
				(font
					(size 1.27 1.27)
				)
				(justify left bottom)
				(hide yes)
			)
		)
		(property "Public" "False"
			(at 162.56 142.24 0)
			(effects
				(font
					(size 1.27 1.27)
				)
				(justify left bottom)
				(hide yes)
			)
		)
		(pin "1"
		)
		(pin "2"
		)
		(instances
			(project "com-express-7-baseboard"
				(path ""
					(reference "C8")
					(unit 1)
				)
			)
		)
	)
	(symbol
		(lib_id "antmicropower:GND")
		(at 261.62 106.68 0)
		(mirror y)
		(unit 1)
		(exclude_from_sim no)
		(in_bom yes)
		(on_board yes)
		(dnp no)
		(property "Reference" "#PWR025"
			(at 252.73 109.22 0)
			(effects
				(font
					(size 1.27 1.27)
					(thickness 0.15)
				)
				(justify left bottom)
				(hide yes)
			)
		)
		(property "Value" "GND"
			(at 261.62 110.49 0)
			(effects
				(font
					(size 1.27 1.27)
					(thickness 0.15)
				)
			)
		)
		(property "Footprint" ""
			(at 252.73 114.3 0)
			(effects
				(font
					(size 1.27 1.27)
					(thickness 0.15)
				)
				(justify left bottom)
				(hide yes)
			)
		)
		(property "Datasheet" ""
			(at 252.73 119.38 0)
			(effects
				(font
					(size 1.27 1.27)
					(thickness 0.15)
				)
				(justify left bottom)
				(hide yes)
			)
		)
		(property "Description" ""
			(at 261.62 106.68 0)
			(effects
				(font
					(size 1.27 1.27)
				)
				(hide yes)
			)
		)
		(property "Author" "Antmicro"
			(at 252.73 114.3 0)
			(effects
				(font
					(size 1.27 1.27)
					(thickness 0.15)
				)
				(justify left bottom)
				(hide yes)
			)
		)
		(property "License" "Apache-2.0"
			(at 252.73 116.84 0)
			(effects
				(font
					(size 1.27 1.27)
					(thickness 0.15)
				)
				(justify left bottom)
				(hide yes)
			)
		)
		(pin "1"
		)
		(instances
			(project "com-express-7-baseboard"
				(path ""
					(reference "#PWR025")
					(unit 1)
				)
			)
		)
	)
	(symbol
		(lib_id "antmicropower:GND")
		(at 280.67 219.71 0)
		(unit 1)
		(exclude_from_sim no)
		(in_bom yes)
		(on_board yes)
		(dnp no)
		(property "Reference" "#PWR034"
			(at 280.67 226.06 0)
			(effects
				(font
					(size 1.27 1.27)
				)
				(justify left bottom)
				(hide yes)
			)
		)
		(property "Value" "GND"
			(at 280.67 223.52 0)
			(effects
				(font
					(size 1.27 1.27)
				)
			)
		)
		(property "Footprint" ""
			(at 280.67 219.71 0)
			(effects
				(font
					(size 1.27 1.27)
				)
				(justify left bottom)
				(hide yes)
			)
		)
		(property "Datasheet" ""
			(at 280.67 219.71 0)
			(effects
				(font
					(size 1.27 1.27)
				)
				(justify left bottom)
				(hide yes)
			)
		)
		(property "Description" ""
			(at 280.67 219.71 0)
			(effects
				(font
					(size 1.27 1.27)
				)
				(hide yes)
			)
		)
		(property "Author" "Antmicro"
			(at 289.56 227.33 0)
			(effects
				(font
					(size 1.27 1.27)
					(thickness 0.15)
				)
				(justify left bottom)
				(hide yes)
			)
		)
		(property "License" "Apache-2.0"
			(at 289.56 229.87 0)
			(effects
				(font
					(size 1.27 1.27)
					(thickness 0.15)
				)
				(justify left bottom)
				(hide yes)
			)
		)
		(pin "1"
		)
		(instances
			(project "com-express-7-baseboard"
				(path ""
					(reference "#PWR034")
					(unit 1)
				)
			)
		)
	)
	(symbol
		(lib_id "antmicroCommonModeChokes:Choke_SRF2012A-801Y")
		(at 220.98 91.44 0)
		(mirror y)
		(unit 1)
		(exclude_from_sim no)
		(in_bom yes)
		(on_board yes)
		(dnp no)
		(fields_autoplaced yes)
		(property "Reference" "T4"
			(at 216.281 86.36 0)
			(effects
				(font
					(size 1.27 1.27)
					(thickness 0.15)
				)
			)
		)
		(property "Value" "Choke_SRF2012A-801Y"
			(at 205.74 101.6 0)
			(effects
				(font
					(size 1.27 1.27)
					(thickness 0.15)
				)
				(justify left bottom)
				(hide yes)
			)
		)
		(property "Footprint" "antmicro-footprints:Choke_0805_2012Metric"
			(at 194.31 104.14 0)
			(effects
				(font
					(size 1.27 1.27)
					(thickness 0.15)
				)
				(justify left bottom)
				(hide yes)
			)
		)
		(property "Datasheet" "https://www.bourns.com/docs/product-datasheets/srf2012a-801y.pdf"
			(at 205.74 106.68 0)
			(effects
				(font
					(size 1.27 1.27)
					(thickness 0.15)
				)
				(justify left bottom)
				(hide yes)
			)
		)
		(property "Description" ""
			(at 220.98 91.44 0)
			(effects
				(font
					(size 1.27 1.27)
				)
				(hide yes)
			)
		)
		(property "Manufacturer" "Bourns"
			(at 205.74 109.22 0)
			(effects
				(font
					(size 1.27 1.27)
					(thickness 0.15)
				)
				(justify left bottom)
				(hide yes)
			)
		)
		(property "MPN" "SRF2012A-801Y"
			(at 216.281 88.9 0)
			(effects
				(font
					(size 1.27 1.27)
					(thickness 0.15)
				)
			)
		)
		(property "IMax" "0.3 A"
			(at 205.74 111.76 0)
			(effects
				(font
					(size 1.27 1.27)
					(thickness 0.15)
				)
				(justify left bottom)
				(hide yes)
			)
		)
		(property "Author" "Antmicro"
			(at 205.74 114.3 0)
			(effects
				(font
					(size 1.27 1.27)
					(thickness 0.15)
				)
				(justify left bottom)
				(hide yes)
			)
		)
		(property "License" "Apache-2.0"
			(at 205.74 116.84 0)
			(effects
				(font
					(size 1.27 1.27)
					(thickness 0.15)
				)
				(justify left bottom)
				(hide yes)
			)
		)
		(property "Public" "False"
			(at 194.31 124.46 0)
			(effects
				(font
					(size 1.27 1.27)
				)
				(justify left bottom)
				(hide yes)
			)
		)
		(pin "3"
		)
		(pin "4"
		)
		(pin "1"
		)
		(pin "2"
		)
		(instances
			(project "com-express-7-baseboard"
				(path ""
					(reference "T4")
					(unit 1)
				)
			)
		)
	)
	(symbol
		(lib_id "antmicroResistors0402:R_0R_0402")
		(at 270.51 49.53 0)
		(unit 1)
		(exclude_from_sim no)
		(in_bom yes)
		(on_board yes)
		(dnp no)
		(property "Reference" "R30"
			(at 269.24 48.26 0)
			(effects
				(font
					(size 1.27 1.27)
					(thickness 0.15)
				)
			)
		)
		(property "Value" "R_0R_0402"
			(at 290.83 62.23 0)
			(effects
				(font
					(size 1.27 1.27)
					(thickness 0.15)
				)
				(justify left bottom)
				(hide yes)
			)
		)
		(property "Footprint" "antmicro-footprints:R_0402_1005Metric"
			(at 290.83 64.77 0)
			(effects
				(font
					(size 1.27 1.27)
					(thickness 0.15)
				)
				(justify left bottom)
				(hide yes)
			)
		)
		(property "Datasheet" "https://industrial.panasonic.com/cdbs/www-data/pdf/RDA0000/AOA0000C301.pdf"
			(at 290.83 67.31 0)
			(effects
				(font
					(size 1.27 1.27)
					(thickness 0.15)
				)
				(justify left bottom)
				(hide yes)
			)
		)
		(property "Description" ""
			(at 270.51 49.53 0)
			(effects
				(font
					(size 1.27 1.27)
				)
				(hide yes)
			)
		)
		(property "MPN" "ERJ2GE0R00X"
			(at 290.83 69.85 0)
			(effects
				(font
					(size 1.27 1.27)
					(thickness 0.15)
				)
				(justify left bottom)
				(hide yes)
			)
		)
		(property "Manufacturer" "Panasonic"
			(at 290.83 72.39 0)
			(effects
				(font
					(size 1.27 1.27)
					(thickness 0.15)
				)
				(justify left bottom)
				(hide yes)
			)
		)
		(property "License" "Apache-2.0"
			(at 290.83 74.93 0)
			(effects
				(font
					(size 1.27 1.27)
					(thickness 0.15)
				)
				(justify left bottom)
				(hide yes)
			)
		)
		(property "Author" "Antmicro"
			(at 290.83 77.47 0)
			(effects
				(font
					(size 1.27 1.27)
					(thickness 0.15)
				)
				(justify left bottom)
				(hide yes)
			)
		)
		(property "Val" "0R"
			(at 276.86 48.26 0)
			(effects
				(font
					(size 1.27 1.27)
					(thickness 0.15)
				)
			)
		)
		(property "Tolerance" "~"
			(at 290.83 59.69 0)
			(effects
				(font
					(size 1.27 1.27)
				)
				(justify left bottom)
				(hide yes)
			)
		)
		(property "Current" "1A"
			(at 290.83 80.01 0)
			(effects
				(font
					(size 1.27 1.27)
					(thickness 0.15)
				)
				(justify left bottom)
				(hide yes)
			)
		)
		(property "Public" "False"
			(at 290.83 80.01 0)
			(effects
				(font
					(size 1.27 1.27)
				)
				(justify left bottom)
				(hide yes)
			)
		)
		(pin "1"
		)
		(pin "2"
		)
		(instances
			(project "com-express-7-baseboard"
				(path ""
					(reference "R30")
					(unit 1)
				)
			)
		)
	)
	(symbol
		(lib_id "antmicroInterfaceDriversReceiversTransceivers:Trans_SM453229-381N7Y")
		(at 245.11 78.74 0)
		(unit 1)
		(exclude_from_sim no)
		(in_bom yes)
		(on_board yes)
		(dnp no)
		(fields_autoplaced yes)
		(property "Reference" "T7"
			(at 250.19 73.66 0)
			(effects
				(font
					(size 1.27 1.27)
					(thickness 0.15)
				)
			)
		)
		(property "Value" "Trans_SM453229-381N7Y"
			(at 271.78 91.44 0)
			(effects
				(font
					(size 1.27 1.27)
					(thickness 0.15)
				)
				(justify left bottom)
				(hide yes)
			)
		)
		(property "Footprint" "antmicro-footprints:Trans_Eth_4.7x3.3mm"
			(at 271.78 93.98 0)
			(effects
				(font
					(size 1.27 1.27)
					(thickness 0.15)
				)
				(justify left bottom)
				(hide yes)
			)
		)
		(property "Datasheet" "https://eu.mouser.com/datasheet/2/54/bourns_02132019_SM453229-381N7Y_datasheet-1532071.pdf"
			(at 271.78 96.52 0)
			(effects
				(font
					(size 1.27 1.27)
					(thickness 0.15)
				)
				(justify left bottom)
				(hide yes)
			)
		)
		(property "Description" ""
			(at 245.11 78.74 0)
			(effects
				(font
					(size 1.27 1.27)
				)
				(hide yes)
			)
		)
		(property "MPN" "SM453229-381N7Y"
			(at 250.19 76.2 0)
			(effects
				(font
					(size 1.27 1.27)
					(thickness 0.15)
				)
			)
		)
		(property "Manufacturer" "Bourns"
			(at 271.78 88.9 0)
			(effects
				(font
					(size 1.27 1.27)
					(thickness 0.15)
				)
				(justify left bottom)
				(hide yes)
			)
		)
		(property "Author" "Antmicro"
			(at 271.78 99.06 0)
			(effects
				(font
					(size 1.27 1.27)
					(thickness 0.15)
				)
				(justify left bottom)
				(hide yes)
			)
		)
		(property "License" "Apache-2.0"
			(at 271.78 101.6 0)
			(effects
				(font
					(size 1.27 1.27)
					(thickness 0.15)
				)
				(justify left bottom)
				(hide yes)
			)
		)
		(pin "7"
		)
		(pin "3"
		)
		(pin "1"
		)
		(pin "5"
		)
		(pin "2"
		)
		(pin "6"
		)
		(instances
			(project "com-express-7-baseboard"
				(path ""
					(reference "T7")
					(unit 1)
				)
			)
		)
	)
	(symbol
		(lib_id "antmicropower:GND")
		(at 133.35 76.2 0)
		(mirror y)
		(unit 1)
		(exclude_from_sim no)
		(in_bom yes)
		(on_board yes)
		(dnp no)
		(property "Reference" "#PWR0474"
			(at 124.46 78.74 0)
			(effects
				(font
					(size 1.27 1.27)
					(thickness 0.15)
				)
				(justify left bottom)
				(hide yes)
			)
		)
		(property "Value" "GND"
			(at 133.35 80.01 0)
			(effects
				(font
					(size 1.27 1.27)
					(thickness 0.15)
				)
			)
		)
		(property "Footprint" ""
			(at 124.46 83.82 0)
			(effects
				(font
					(size 1.27 1.27)
					(thickness 0.15)
				)
				(justify left bottom)
				(hide yes)
			)
		)
		(property "Datasheet" ""
			(at 124.46 88.9 0)
			(effects
				(font
					(size 1.27 1.27)
					(thickness 0.15)
				)
				(justify left bottom)
				(hide yes)
			)
		)
		(property "Description" ""
			(at 133.35 76.2 0)
			(effects
				(font
					(size 1.27 1.27)
				)
				(hide yes)
			)
		)
		(property "Author" "Antmicro"
			(at 124.46 83.82 0)
			(effects
				(font
					(size 1.27 1.27)
					(thickness 0.15)
				)
				(justify left bottom)
				(hide yes)
			)
		)
		(property "License" "Apache-2.0"
			(at 124.46 86.36 0)
			(effects
				(font
					(size 1.27 1.27)
					(thickness 0.15)
				)
				(justify left bottom)
				(hide yes)
			)
		)
		(pin "1"
		)
		(instances
			(project "com-express-7-baseboard"
				(path ""
					(reference "#PWR0474")
					(unit 1)
				)
			)
		)
	)
	(symbol
		(lib_id "antmicroInterfaceDriversReceiversTransceivers:Trans_SM453229-381N7Y")
		(at 245.11 53.34 0)
		(unit 1)
		(exclude_from_sim no)
		(in_bom yes)
		(on_board yes)
		(dnp no)
		(property "Reference" "T5"
			(at 250.19 48.26 0)
			(effects
				(font
					(size 1.27 1.27)
					(thickness 0.15)
				)
			)
		)
		(property "Value" "Trans_SM453229-381N7Y"
			(at 271.78 66.04 0)
			(effects
				(font
					(size 1.27 1.27)
					(thickness 0.15)
				)
				(justify left bottom)
				(hide yes)
			)
		)
		(property "Footprint" "antmicro-footprints:Trans_Eth_4.7x3.3mm"
			(at 271.78 68.58 0)
			(effects
				(font
					(size 1.27 1.27)
					(thickness 0.15)
				)
				(justify left bottom)
				(hide yes)
			)
		)
		(property "Datasheet" "https://eu.mouser.com/datasheet/2/54/bourns_02132019_SM453229-381N7Y_datasheet-1532071.pdf"
			(at 271.78 71.12 0)
			(effects
				(font
					(size 1.27 1.27)
					(thickness 0.15)
				)
				(justify left bottom)
				(hide yes)
			)
		)
		(property "Description" ""
			(at 245.11 53.34 0)
			(effects
				(font
					(size 1.27 1.27)
				)
				(hide yes)
			)
		)
		(property "MPN" "SM453229-381N7Y"
			(at 250.19 50.8 0)
			(effects
				(font
					(size 1.27 1.27)
					(thickness 0.15)
				)
			)
		)
		(property "Manufacturer" "Bourns"
			(at 271.78 63.5 0)
			(effects
				(font
					(size 1.27 1.27)
					(thickness 0.15)
				)
				(justify left bottom)
				(hide yes)
			)
		)
		(property "Author" "Antmicro"
			(at 271.78 73.66 0)
			(effects
				(font
					(size 1.27 1.27)
					(thickness 0.15)
				)
				(justify left bottom)
				(hide yes)
			)
		)
		(property "License" "Apache-2.0"
			(at 271.78 76.2 0)
			(effects
				(font
					(size 1.27 1.27)
					(thickness 0.15)
				)
				(justify left bottom)
				(hide yes)
			)
		)
		(pin "7"
		)
		(pin "3"
		)
		(pin "1"
		)
		(pin "5"
		)
		(pin "2"
		)
		(pin "6"
		)
		(instances
			(project "com-express-7-baseboard"
				(path ""
					(reference "T5")
					(unit 1)
				)
			)
		)
	)
	(symbol
		(lib_id "antmicropower:+3V3")
		(at 134.62 50.8 0)
		(unit 1)
		(exclude_from_sim no)
		(in_bom yes)
		(on_board yes)
		(dnp no)
		(property "Reference" "#PWR01"
			(at 149.86 50.8 0)
			(effects
				(font
					(size 1.27 1.27)
					(thickness 0.15)
				)
				(justify left bottom)
				(hide yes)
			)
		)
		(property "Value" "+3V3"
			(at 134.62 46.99 0)
			(effects
				(font
					(size 1.27 1.27)
					(thickness 0.15)
				)
			)
		)
		(property "Footprint" ""
			(at 149.86 58.42 0)
			(effects
				(font
					(size 1.27 1.27)
					(thickness 0.15)
				)
				(justify left bottom)
				(hide yes)
			)
		)
		(property "Datasheet" ""
			(at 149.86 60.96 0)
			(effects
				(font
					(size 1.27 1.27)
					(thickness 0.15)
				)
				(justify left bottom)
				(hide yes)
			)
		)
		(property "Description" ""
			(at 134.62 50.8 0)
			(effects
				(font
					(size 1.27 1.27)
				)
				(hide yes)
			)
		)
		(property "Author" "Antmicro"
			(at 149.86 53.34 0)
			(effects
				(font
					(size 1.27 1.27)
					(thickness 0.15)
				)
				(justify left bottom)
				(hide yes)
			)
		)
		(property "License" "Apache-2.0"
			(at 149.86 55.88 0)
			(effects
				(font
					(size 1.27 1.27)
					(thickness 0.15)
				)
				(justify left bottom)
				(hide yes)
			)
		)
		(pin "1"
		)
		(instances
			(project "com-express-7-baseboard"
				(path ""
					(reference "#PWR01")
					(unit 1)
				)
			)
		)
	)
	(symbol
		(lib_id "antmicropower:GND")
		(at 237.49 175.26 0)
		(mirror y)
		(unit 1)
		(exclude_from_sim no)
		(in_bom yes)
		(on_board yes)
		(dnp no)
		(property "Reference" "#PWR021"
			(at 228.6 177.8 0)
			(effects
				(font
					(size 1.27 1.27)
					(thickness 0.15)
				)
				(justify left bottom)
				(hide yes)
			)
		)
		(property "Value" "GND"
			(at 241.3 176.53 0)
			(effects
				(font
					(size 1.27 1.27)
					(thickness 0.15)
				)
			)
		)
		(property "Footprint" ""
			(at 228.6 182.88 0)
			(effects
				(font
					(size 1.27 1.27)
					(thickness 0.15)
				)
				(justify left bottom)
				(hide yes)
			)
		)
		(property "Datasheet" ""
			(at 228.6 187.96 0)
			(effects
				(font
					(size 1.27 1.27)
					(thickness 0.15)
				)
				(justify left bottom)
				(hide yes)
			)
		)
		(property "Description" ""
			(at 237.49 175.26 0)
			(effects
				(font
					(size 1.27 1.27)
				)
				(hide yes)
			)
		)
		(property "Author" "Antmicro"
			(at 228.6 182.88 0)
			(effects
				(font
					(size 1.27 1.27)
					(thickness 0.15)
				)
				(justify left bottom)
				(hide yes)
			)
		)
		(property "License" "Apache-2.0"
			(at 228.6 185.42 0)
			(effects
				(font
					(size 1.27 1.27)
					(thickness 0.15)
				)
				(justify left bottom)
				(hide yes)
			)
		)
		(pin "1"
		)
		(instances
			(project "com-express-7-baseboard"
				(path ""
					(reference "#PWR021")
					(unit 1)
				)
			)
		)
	)
	(symbol
		(lib_id "antmicroCapacitors0402:C_100n_0402")
		(at 270.51 148.59 270)
		(mirror x)
		(unit 1)
		(exclude_from_sim no)
		(in_bom yes)
		(on_board yes)
		(dnp no)
		(fields_autoplaced yes)
		(property "Reference" "C16"
			(at 267.97 144.7735 90)
			(effects
				(font
					(size 1.27 1.27)
					(thickness 0.15)
				)
				(justify right)
			)
		)
		(property "Value" "C_100n_0402"
			(at 260.35 128.27 0)
			(effects
				(font
					(size 1.27 1.27)
					(thickness 0.15)
				)
				(justify left bottom)
				(hide yes)
			)
		)
		(property "Footprint" "antmicro-footprints:C_0402_1005Metric"
			(at 257.81 128.27 0)
			(effects
				(font
					(size 1.27 1.27)
					(thickness 0.15)
				)
				(justify left bottom)
				(hide yes)
			)
		)
		(property "Datasheet" "https://www.murata.com/products/productdetail?partno=GRM155R61H104KE14%23"
			(at 255.27 128.27 0)
			(effects
				(font
					(size 1.27 1.27)
					(thickness 0.15)
				)
				(justify left bottom)
				(hide yes)
			)
		)
		(property "Description" ""
			(at 270.51 148.59 0)
			(effects
				(font
					(size 1.27 1.27)
				)
				(hide yes)
			)
		)
		(property "MPN" "GRM155R61H104KE14D"
			(at 252.73 128.27 0)
			(effects
				(font
					(size 1.27 1.27)
					(thickness 0.15)
				)
				(justify left bottom)
				(hide yes)
			)
		)
		(property "Manufacturer" "Murata"
			(at 250.19 128.27 0)
			(effects
				(font
					(size 1.27 1.27)
					(thickness 0.15)
				)
				(justify left bottom)
				(hide yes)
			)
		)
		(property "License" "Apache-2.0"
			(at 247.65 128.27 0)
			(effects
				(font
					(size 1.27 1.27)
					(thickness 0.15)
				)
				(justify left bottom)
				(hide yes)
			)
		)
		(property "Author" "Antmicro"
			(at 245.11 128.27 0)
			(effects
				(font
					(size 1.27 1.27)
					(thickness 0.15)
				)
				(justify left bottom)
				(hide yes)
			)
		)
		(property "Val" "100n"
			(at 267.97 147.3135 90)
			(effects
				(font
					(size 1.27 1.27)
					(thickness 0.15)
				)
				(justify right)
			)
		)
		(property "Voltage" "50V"
			(at 242.57 128.27 0)
			(effects
				(font
					(size 1.27 1.27)
				)
				(justify left bottom)
				(hide yes)
			)
		)
		(property "Dielectric" "X5R"
			(at 240.03 128.27 0)
			(effects
				(font
					(size 1.27 1.27)
				)
				(justify left bottom)
				(hide yes)
			)
		)
		(property "Public" "False"
			(at 237.49 128.27 0)
			(effects
				(font
					(size 1.27 1.27)
				)
				(justify left bottom)
				(hide yes)
			)
		)
		(pin "1"
		)
		(pin "2"
		)
		(instances
			(project "com-express-7-baseboard"
				(path ""
					(reference "C16")
					(unit 1)
				)
			)
		)
	)
	(symbol
		(lib_id "antmicropower:GND")
		(at 204.47 163.83 0)
		(unit 1)
		(exclude_from_sim no)
		(in_bom yes)
		(on_board yes)
		(dnp no)
		(property "Reference" "#PWR016"
			(at 204.47 170.18 0)
			(effects
				(font
					(size 1.27 1.27)
				)
				(justify left bottom)
				(hide yes)
			)
		)
		(property "Value" "GND"
			(at 204.47 167.64 0)
			(effects
				(font
					(size 1.27 1.27)
				)
			)
		)
		(property "Footprint" ""
			(at 204.47 163.83 0)
			(effects
				(font
					(size 1.27 1.27)
				)
				(hide yes)
			)
		)
		(property "Datasheet" ""
			(at 204.47 163.83 0)
			(effects
				(font
					(size 1.27 1.27)
				)
				(hide yes)
			)
		)
		(property "Description" ""
			(at 204.47 163.83 0)
			(effects
				(font
					(size 1.27 1.27)
				)
				(hide yes)
			)
		)
		(property "Author" "Antmicro"
			(at 213.36 171.45 0)
			(effects
				(font
					(size 1.27 1.27)
					(thickness 0.15)
				)
				(justify left bottom)
				(hide yes)
			)
		)
		(property "License" "Apache-2.0"
			(at 213.36 173.99 0)
			(effects
				(font
					(size 1.27 1.27)
					(thickness 0.15)
				)
				(justify left bottom)
				(hide yes)
			)
		)
		(pin "1"
		)
		(instances
			(project "com-express-7-baseboard"
				(path ""
					(reference "#PWR016")
					(unit 1)
				)
			)
		)
	)
	(symbol
		(lib_id "antmicroResistors0402:R_470R_0402")
		(at 133.35 73.66 90)
		(unit 1)
		(exclude_from_sim no)
		(in_bom yes)
		(on_board yes)
		(dnp yes)
		(property "Reference" "R331"
			(at 134.62 69.85 90)
			(effects
				(font
					(size 1.27 1.27)
					(thickness 0.15)
				)
				(justify right)
			)
		)
		(property "Value" "R_470R_0402"
			(at 146.05 53.34 0)
			(effects
				(font
					(size 1.27 1.27)
					(thickness 0.15)
				)
				(justify left bottom)
				(hide yes)
			)
		)
		(property "Footprint" "antmicro-footprints:R_0402_1005Metric"
			(at 148.59 53.34 0)
			(effects
				(font
					(size 1.27 1.27)
					(thickness 0.15)
				)
				(justify left bottom)
				(hide yes)
			)
		)
		(property "Datasheet" "https://www.bourns.com/docs/product-datasheets/cr.pdf"
			(at 151.13 53.34 0)
			(effects
				(font
					(size 1.27 1.27)
					(thickness 0.15)
				)
				(justify left bottom)
				(hide yes)
			)
		)
		(property "Description" ""
			(at 133.35 73.66 0)
			(effects
				(font
					(size 1.27 1.27)
				)
				(hide yes)
			)
		)
		(property "MPN" "CR0402-FX-4700GLF"
			(at 153.67 53.34 0)
			(effects
				(font
					(size 1.27 1.27)
					(thickness 0.15)
				)
				(justify left bottom)
				(hide yes)
			)
		)
		(property "Manufacturer" "Bourns"
			(at 156.21 53.34 0)
			(effects
				(font
					(size 1.27 1.27)
					(thickness 0.15)
				)
				(justify left bottom)
				(hide yes)
			)
		)
		(property "License" "Apache-2.0"
			(at 158.75 53.34 0)
			(effects
				(font
					(size 1.27 1.27)
					(thickness 0.15)
				)
				(justify left bottom)
				(hide yes)
			)
		)
		(property "Author" "Antmicro"
			(at 161.29 53.34 0)
			(effects
				(font
					(size 1.27 1.27)
					(thickness 0.15)
				)
				(justify left bottom)
				(hide yes)
			)
		)
		(property "Val" "470R"
			(at 134.62 72.39 90)
			(effects
				(font
					(size 1.27 1.27)
					(thickness 0.15)
				)
				(justify right)
			)
		)
		(property "Tolerance" "1%"
			(at 143.51 53.34 0)
			(effects
				(font
					(size 1.27 1.27)
				)
				(justify left bottom)
				(hide yes)
			)
		)
		(property "Public" "False"
			(at 163.83 53.34 0)
			(effects
				(font
					(size 1.27 1.27)
				)
				(justify left bottom)
				(hide yes)
			)
		)
		(pin "2"
		)
		(pin "1"
		)
		(instances
			(project "com-express-7-baseboard"
				(path ""
					(reference "R331")
					(unit 1)
				)
			)
		)
	)
	(symbol
		(lib_id "antmicroCapacitorsmisc:C_1n_1210_2kV")
		(at 232.41 105.41 90)
		(unit 1)
		(exclude_from_sim no)
		(in_bom yes)
		(on_board yes)
		(dnp no)
		(fields_autoplaced yes)
		(property "Reference" "C12"
			(at 234.95 101.5936 90)
			(effects
				(font
					(size 1.27 1.27)
					(thickness 0.15)
				)
				(justify right)
			)
		)
		(property "Value" "C_1n_1210_2kV"
			(at 242.57 85.09 0)
			(effects
				(font
					(size 1.27 1.27)
					(thickness 0.15)
				)
				(justify left bottom)
				(hide yes)
			)
		)
		(property "Footprint" "antmicro-footprints:C_1210_3225Metric"
			(at 245.11 85.09 0)
			(effects
				(font
					(size 1.27 1.27)
					(thickness 0.15)
				)
				(justify left bottom)
				(hide yes)
			)
		)
		(property "Datasheet" "https://www.kemet.com/en/us/capacitors/product/C1210C102KGRACTU.html"
			(at 247.65 85.09 0)
			(effects
				(font
					(size 1.27 1.27)
					(thickness 0.15)
				)
				(justify left bottom)
				(hide yes)
			)
		)
		(property "Description" ""
			(at 232.41 105.41 0)
			(effects
				(font
					(size 1.27 1.27)
				)
				(hide yes)
			)
		)
		(property "MPN" "C1210C102KGRACTU"
			(at 250.19 85.09 0)
			(effects
				(font
					(size 1.27 1.27)
					(thickness 0.15)
				)
				(justify left bottom)
				(hide yes)
			)
		)
		(property "Manufacturer" "KEMET"
			(at 252.73 85.09 0)
			(effects
				(font
					(size 1.27 1.27)
					(thickness 0.15)
				)
				(justify left bottom)
				(hide yes)
			)
		)
		(property "License" "Apache-2.0"
			(at 255.27 85.09 0)
			(effects
				(font
					(size 1.27 1.27)
					(thickness 0.15)
				)
				(justify left bottom)
				(hide yes)
			)
		)
		(property "Author" "Antmicro"
			(at 257.81 85.09 0)
			(effects
				(font
					(size 1.27 1.27)
					(thickness 0.15)
				)
				(justify left bottom)
				(hide yes)
			)
		)
		(property "Val" "1n"
			(at 234.95 104.1336 90)
			(effects
				(font
					(size 1.27 1.27)
					(thickness 0.15)
				)
				(justify right)
			)
		)
		(property "Voltage" "2kV"
			(at 260.35 85.09 0)
			(effects
				(font
					(size 1.27 1.27)
				)
				(justify left bottom)
				(hide yes)
			)
		)
		(property "Dielectric" ""
			(at 262.89 85.09 0)
			(effects
				(font
					(size 1.27 1.27)
				)
				(justify left bottom)
				(hide yes)
			)
		)
		(property "Public" "False"
			(at 265.43 85.09 0)
			(effects
				(font
					(size 1.27 1.27)
				)
				(justify left bottom)
				(hide yes)
			)
		)
		(pin "1"
		)
		(pin "2"
		)
		(instances
			(project "com-express-7-baseboard"
				(path ""
					(reference "C12")
					(unit 1)
				)
			)
		)
	)
	(symbol
		(lib_id "antmicroResistors0402:R_470R_0402")
		(at 128.27 59.69 90)
		(unit 1)
		(exclude_from_sim no)
		(in_bom yes)
		(on_board yes)
		(dnp yes)
		(property "Reference" "R7"
			(at 127 55.88 90)
			(effects
				(font
					(size 1.27 1.27)
					(thickness 0.15)
				)
				(justify left)
			)
		)
		(property "Value" "R_470R_0402"
			(at 140.97 39.37 0)
			(effects
				(font
					(size 1.27 1.27)
					(thickness 0.15)
				)
				(justify left bottom)
				(hide yes)
			)
		)
		(property "Footprint" "antmicro-footprints:R_0402_1005Metric"
			(at 143.51 39.37 0)
			(effects
				(font
					(size 1.27 1.27)
					(thickness 0.15)
				)
				(justify left bottom)
				(hide yes)
			)
		)
		(property "Datasheet" "https://www.bourns.com/docs/product-datasheets/cr.pdf"
			(at 146.05 39.37 0)
			(effects
				(font
					(size 1.27 1.27)
					(thickness 0.15)
				)
				(justify left bottom)
				(hide yes)
			)
		)
		(property "Description" ""
			(at 128.27 59.69 0)
			(effects
				(font
					(size 1.27 1.27)
				)
				(hide yes)
			)
		)
		(property "MPN" "CR0402-FX-4700GLF"
			(at 148.59 39.37 0)
			(effects
				(font
					(size 1.27 1.27)
					(thickness 0.15)
				)
				(justify left bottom)
				(hide yes)
			)
		)
		(property "Manufacturer" "Bourns"
			(at 151.13 39.37 0)
			(effects
				(font
					(size 1.27 1.27)
					(thickness 0.15)
				)
				(justify left bottom)
				(hide yes)
			)
		)
		(property "License" "Apache-2.0"
			(at 153.67 39.37 0)
			(effects
				(font
					(size 1.27 1.27)
					(thickness 0.15)
				)
				(justify left bottom)
				(hide yes)
			)
		)
		(property "Author" "Antmicro"
			(at 156.21 39.37 0)
			(effects
				(font
					(size 1.27 1.27)
					(thickness 0.15)
				)
				(justify left bottom)
				(hide yes)
			)
		)
		(property "Val" "470R"
			(at 127 58.42 90)
			(effects
				(font
					(size 1.27 1.27)
					(thickness 0.15)
				)
				(justify left)
			)
		)
		(property "Tolerance" "1%"
			(at 138.43 39.37 0)
			(effects
				(font
					(size 1.27 1.27)
				)
				(justify left bottom)
				(hide yes)
			)
		)
		(property "Public" "False"
			(at 158.75 39.37 0)
			(effects
				(font
					(size 1.27 1.27)
				)
				(justify left bottom)
				(hide yes)
			)
		)
		(pin "2"
		)
		(pin "1"
		)
		(instances
			(project "com-express-7-baseboard"
				(path ""
					(reference "R7")
					(unit 1)
				)
			)
		)
	)
	(symbol
		(lib_id "antmicropower:GND")
		(at 187.96 190.5 0)
		(mirror y)
		(unit 1)
		(exclude_from_sim no)
		(in_bom yes)
		(on_board yes)
		(dnp no)
		(property "Reference" "#PWR012"
			(at 179.07 193.04 0)
			(effects
				(font
					(size 1.27 1.27)
					(thickness 0.15)
				)
				(justify left bottom)
				(hide yes)
			)
		)
		(property "Value" "GND"
			(at 187.96 194.31 0)
			(effects
				(font
					(size 1.27 1.27)
					(thickness 0.15)
				)
			)
		)
		(property "Footprint" ""
			(at 179.07 198.12 0)
			(effects
				(font
					(size 1.27 1.27)
					(thickness 0.15)
				)
				(justify left bottom)
				(hide yes)
			)
		)
		(property "Datasheet" ""
			(at 179.07 203.2 0)
			(effects
				(font
					(size 1.27 1.27)
					(thickness 0.15)
				)
				(justify left bottom)
				(hide yes)
			)
		)
		(property "Description" ""
			(at 187.96 190.5 0)
			(effects
				(font
					(size 1.27 1.27)
				)
				(hide yes)
			)
		)
		(property "Author" "Antmicro"
			(at 179.07 198.12 0)
			(effects
				(font
					(size 1.27 1.27)
					(thickness 0.15)
				)
				(justify left bottom)
				(hide yes)
			)
		)
		(property "License" "Apache-2.0"
			(at 179.07 200.66 0)
			(effects
				(font
					(size 1.27 1.27)
					(thickness 0.15)
				)
				(justify left bottom)
				(hide yes)
			)
		)
		(pin "1"
		)
		(instances
			(project "com-express-7-baseboard"
				(path ""
					(reference "#PWR012")
					(unit 1)
				)
			)
		)
	)
	(symbol
		(lib_id "antmicropower:+3V3")
		(at 241.3 218.44 0)
		(unit 1)
		(exclude_from_sim no)
		(in_bom yes)
		(on_board yes)
		(dnp no)
		(property "Reference" "#PWR024"
			(at 256.54 218.44 0)
			(effects
				(font
					(size 1.27 1.27)
					(thickness 0.15)
				)
				(justify left bottom)
				(hide yes)
			)
		)
		(property "Value" "+3V3"
			(at 241.3 214.63 0)
			(effects
				(font
					(size 1.27 1.27)
					(thickness 0.15)
				)
			)
		)
		(property "Footprint" ""
			(at 256.54 226.06 0)
			(effects
				(font
					(size 1.27 1.27)
					(thickness 0.15)
				)
				(justify left bottom)
				(hide yes)
			)
		)
		(property "Datasheet" ""
			(at 256.54 228.6 0)
			(effects
				(font
					(size 1.27 1.27)
					(thickness 0.15)
				)
				(justify left bottom)
				(hide yes)
			)
		)
		(property "Description" ""
			(at 241.3 218.44 0)
			(effects
				(font
					(size 1.27 1.27)
				)
				(hide yes)
			)
		)
		(property "Author" "Antmicro"
			(at 256.54 220.98 0)
			(effects
				(font
					(size 1.27 1.27)
					(thickness 0.15)
				)
				(justify left bottom)
				(hide yes)
			)
		)
		(property "License" "Apache-2.0"
			(at 256.54 223.52 0)
			(effects
				(font
					(size 1.27 1.27)
					(thickness 0.15)
				)
				(justify left bottom)
				(hide yes)
			)
		)
		(pin "1"
		)
		(instances
			(project "com-express-7-baseboard"
				(path ""
					(reference "#PWR024")
					(unit 1)
				)
			)
		)
	)
	(symbol
		(lib_id "antmicroCommonModeChokes:Choke_SRF2012A-801Y")
		(at 220.98 66.04 0)
		(mirror y)
		(unit 1)
		(exclude_from_sim no)
		(in_bom yes)
		(on_board yes)
		(dnp no)
		(fields_autoplaced yes)
		(property "Reference" "T2"
			(at 216.281 60.96 0)
			(effects
				(font
					(size 1.27 1.27)
					(thickness 0.15)
				)
			)
		)
		(property "Value" "Choke_SRF2012A-801Y"
			(at 205.74 76.2 0)
			(effects
				(font
					(size 1.27 1.27)
					(thickness 0.15)
				)
				(justify left bottom)
				(hide yes)
			)
		)
		(property "Footprint" "antmicro-footprints:Choke_0805_2012Metric"
			(at 194.31 78.74 0)
			(effects
				(font
					(size 1.27 1.27)
					(thickness 0.15)
				)
				(justify left bottom)
				(hide yes)
			)
		)
		(property "Datasheet" "https://www.bourns.com/docs/product-datasheets/srf2012a-801y.pdf"
			(at 205.74 81.28 0)
			(effects
				(font
					(size 1.27 1.27)
					(thickness 0.15)
				)
				(justify left bottom)
				(hide yes)
			)
		)
		(property "Description" ""
			(at 220.98 66.04 0)
			(effects
				(font
					(size 1.27 1.27)
				)
				(hide yes)
			)
		)
		(property "Manufacturer" "Bourns"
			(at 205.74 83.82 0)
			(effects
				(font
					(size 1.27 1.27)
					(thickness 0.15)
				)
				(justify left bottom)
				(hide yes)
			)
		)
		(property "MPN" "SRF2012A-801Y"
			(at 216.281 63.5 0)
			(effects
				(font
					(size 1.27 1.27)
					(thickness 0.15)
				)
			)
		)
		(property "IMax" "0.3 A"
			(at 205.74 86.36 0)
			(effects
				(font
					(size 1.27 1.27)
					(thickness 0.15)
				)
				(justify left bottom)
				(hide yes)
			)
		)
		(property "Author" "Antmicro"
			(at 205.74 88.9 0)
			(effects
				(font
					(size 1.27 1.27)
					(thickness 0.15)
				)
				(justify left bottom)
				(hide yes)
			)
		)
		(property "License" "Apache-2.0"
			(at 205.74 91.44 0)
			(effects
				(font
					(size 1.27 1.27)
					(thickness 0.15)
				)
				(justify left bottom)
				(hide yes)
			)
		)
		(property "Public" "False"
			(at 194.31 99.06 0)
			(effects
				(font
					(size 1.27 1.27)
				)
				(justify left bottom)
				(hide yes)
			)
		)
		(pin "3"
		)
		(pin "4"
		)
		(pin "1"
		)
		(pin "2"
		)
		(instances
			(project "com-express-7-baseboard"
				(path ""
					(reference "T2")
					(unit 1)
				)
			)
		)
	)
	(symbol
		(lib_id "antmicroTVSDiodes:ESD204DQAR")
		(at 172.72 190.5 90)
		(mirror x)
		(unit 1)
		(exclude_from_sim no)
		(in_bom yes)
		(on_board yes)
		(dnp no)
		(fields_autoplaced yes)
		(property "Reference" "U1"
			(at 168.91 194.945 90)
			(effects
				(font
					(size 1.27 1.27)
				)
				(justify left)
			)
		)
		(property "Value" "ESD204DQAR"
			(at 187.96 201.93 90)
			(effects
				(font
					(size 1.27 1.27)
					(thickness 0.15)
				)
				(justify left bottom)
				(hide yes)
			)
		)
		(property "Footprint" "antmicro-footprints:USON-10_2.5x1mm_P0.5mm"
			(at 177.8 214.63 0)
			(effects
				(font
					(size 1.27 1.27)
					(thickness 0.15)
				)
				(justify left bottom)
				(hide yes)
			)
		)
		(property "Datasheet" "https://www.ti.com/lit/ds/symlink/esd204.pdf?ts=1706004844383&ref_url=https%253A%252F%252Fwww.ti.com%252Finterface%252Fdiodes%252Fesd-protection-diodes%252Fproducts.html"
			(at 180.34 214.63 0)
			(effects
				(font
					(size 1.27 1.27)
					(thickness 0.15)
				)
				(justify left bottom)
				(hide yes)
			)
		)
		(property "Description" ""
			(at 172.72 190.5 0)
			(effects
				(font
					(size 1.27 1.27)
				)
				(hide yes)
			)
		)
		(property "Manufacturer" "Texas Instruments"
			(at 182.88 214.63 0)
			(effects
				(font
					(size 1.27 1.27)
					(thickness 0.15)
				)
				(justify left bottom)
				(hide yes)
			)
		)
		(property "MPN" "ESD204DQAR"
			(at 168.91 197.485 90)
			(effects
				(font
					(size 1.27 1.27)
					(thickness 0.15)
				)
				(justify left)
			)
		)
		(property "Author" "Antmicro"
			(at 187.96 214.63 0)
			(effects
				(font
					(size 1.27 1.27)
					(thickness 0.15)
				)
				(justify left bottom)
				(hide yes)
			)
		)
		(property "License" "Apache-2.0"
			(at 190.5 214.63 0)
			(effects
				(font
					(size 1.27 1.27)
					(thickness 0.15)
				)
				(justify left bottom)
				(hide yes)
			)
		)
		(pin "1"
		)
		(pin "10"
		)
		(pin "2"
		)
		(pin "3"
		)
		(pin "4"
		)
		(pin "5"
		)
		(pin "6"
		)
		(pin "7"
		)
		(pin "8"
		)
		(pin "9"
		)
		(instances
			(project "com-express-7-baseboard"
				(path ""
					(reference "U1")
					(unit 1)
				)
			)
		)
	)
	(symbol
		(lib_id "antmicroTVSDiodes:ESD204DQAR")
		(at 172.72 260.35 90)
		(mirror x)
		(unit 1)
		(exclude_from_sim no)
		(in_bom yes)
		(on_board yes)
		(dnp no)
		(fields_autoplaced yes)
		(property "Reference" "U2"
			(at 168.91 264.795 90)
			(effects
				(font
					(size 1.27 1.27)
				)
				(justify left)
			)
		)
		(property "Value" "ESD204DQAR"
			(at 187.96 271.78 90)
			(effects
				(font
					(size 1.27 1.27)
					(thickness 0.15)
				)
				(justify left bottom)
				(hide yes)
			)
		)
		(property "Footprint" "antmicro-footprints:USON-10_2.5x1mm_P0.5mm"
			(at 177.8 284.48 0)
			(effects
				(font
					(size 1.27 1.27)
					(thickness 0.15)
				)
				(justify left bottom)
				(hide yes)
			)
		)
		(property "Datasheet" "https://www.ti.com/lit/ds/symlink/esd204.pdf?ts=1706004844383&ref_url=https%253A%252F%252Fwww.ti.com%252Finterface%252Fdiodes%252Fesd-protection-diodes%252Fproducts.html"
			(at 180.34 284.48 0)
			(effects
				(font
					(size 1.27 1.27)
					(thickness 0.15)
				)
				(justify left bottom)
				(hide yes)
			)
		)
		(property "Description" ""
			(at 172.72 260.35 0)
			(effects
				(font
					(size 1.27 1.27)
				)
				(hide yes)
			)
		)
		(property "Manufacturer" "Texas Instruments"
			(at 182.88 284.48 0)
			(effects
				(font
					(size 1.27 1.27)
					(thickness 0.15)
				)
				(justify left bottom)
				(hide yes)
			)
		)
		(property "MPN" "ESD204DQAR"
			(at 168.91 267.335 90)
			(effects
				(font
					(size 1.27 1.27)
					(thickness 0.15)
				)
				(justify left)
			)
		)
		(property "Author" "Antmicro"
			(at 187.96 284.48 0)
			(effects
				(font
					(size 1.27 1.27)
					(thickness 0.15)
				)
				(justify left bottom)
				(hide yes)
			)
		)
		(property "License" "Apache-2.0"
			(at 190.5 284.48 0)
			(effects
				(font
					(size 1.27 1.27)
					(thickness 0.15)
				)
				(justify left bottom)
				(hide yes)
			)
		)
		(pin "1"
		)
		(pin "10"
		)
		(pin "2"
		)
		(pin "3"
		)
		(pin "4"
		)
		(pin "5"
		)
		(pin "6"
		)
		(pin "7"
		)
		(pin "8"
		)
		(pin "9"
		)
		(instances
			(project "com-express-7-baseboard"
				(path ""
					(reference "U2")
					(unit 1)
				)
			)
		)
	)
	(symbol
		(lib_id "antmicropower:GND")
		(at 182.88 163.83 0)
		(mirror y)
		(unit 1)
		(exclude_from_sim no)
		(in_bom yes)
		(on_board yes)
		(dnp no)
		(property "Reference" "#PWR010"
			(at 173.99 166.37 0)
			(effects
				(font
					(size 1.27 1.27)
					(thickness 0.15)
				)
				(justify left bottom)
				(hide yes)
			)
		)
		(property "Value" "GND"
			(at 182.88 167.64 0)
			(effects
				(font
					(size 1.27 1.27)
					(thickness 0.15)
				)
			)
		)
		(property "Footprint" ""
			(at 173.99 171.45 0)
			(effects
				(font
					(size 1.27 1.27)
					(thickness 0.15)
				)
				(justify left bottom)
				(hide yes)
			)
		)
		(property "Datasheet" ""
			(at 173.99 176.53 0)
			(effects
				(font
					(size 1.27 1.27)
					(thickness 0.15)
				)
				(justify left bottom)
				(hide yes)
			)
		)
		(property "Description" ""
			(at 182.88 163.83 0)
			(effects
				(font
					(size 1.27 1.27)
				)
				(hide yes)
			)
		)
		(property "Author" "Antmicro"
			(at 173.99 171.45 0)
			(effects
				(font
					(size 1.27 1.27)
					(thickness 0.15)
				)
				(justify left bottom)
				(hide yes)
			)
		)
		(property "License" "Apache-2.0"
			(at 173.99 173.99 0)
			(effects
				(font
					(size 1.27 1.27)
					(thickness 0.15)
				)
				(justify left bottom)
				(hide yes)
			)
		)
		(pin "1"
		)
		(instances
			(project "com-express-7-baseboard"
				(path ""
					(reference "#PWR010")
					(unit 1)
				)
			)
		)
	)
	(symbol
		(lib_id "antmicroResistors0402:R_0R_0402")
		(at 254 227.33 0)
		(mirror y)
		(unit 1)
		(exclude_from_sim no)
		(in_bom yes)
		(on_board yes)
		(dnp no)
		(property "Reference" "R28"
			(at 256.54 226.06 0)
			(effects
				(font
					(size 1.27 1.27)
					(thickness 0.15)
				)
			)
		)
		(property "Value" "R_0R_0402"
			(at 233.68 240.03 0)
			(effects
				(font
					(size 1.27 1.27)
					(thickness 0.15)
				)
				(justify left bottom)
				(hide yes)
			)
		)
		(property "Footprint" "antmicro-footprints:R_0402_1005Metric"
			(at 233.68 242.57 0)
			(effects
				(font
					(size 1.27 1.27)
					(thickness 0.15)
				)
				(justify left bottom)
				(hide yes)
			)
		)
		(property "Datasheet" "https://industrial.panasonic.com/cdbs/www-data/pdf/RDA0000/AOA0000C301.pdf"
			(at 233.68 245.11 0)
			(effects
				(font
					(size 1.27 1.27)
					(thickness 0.15)
				)
				(justify left bottom)
				(hide yes)
			)
		)
		(property "Description" ""
			(at 254 227.33 0)
			(effects
				(font
					(size 1.27 1.27)
				)
				(hide yes)
			)
		)
		(property "MPN" "ERJ2GE0R00X"
			(at 233.68 247.65 0)
			(effects
				(font
					(size 1.27 1.27)
					(thickness 0.15)
				)
				(justify left bottom)
				(hide yes)
			)
		)
		(property "Manufacturer" "Panasonic"
			(at 233.68 250.19 0)
			(effects
				(font
					(size 1.27 1.27)
					(thickness 0.15)
				)
				(justify left bottom)
				(hide yes)
			)
		)
		(property "License" "Apache-2.0"
			(at 233.68 252.73 0)
			(effects
				(font
					(size 1.27 1.27)
					(thickness 0.15)
				)
				(justify left bottom)
				(hide yes)
			)
		)
		(property "Author" "Antmicro"
			(at 233.68 255.27 0)
			(effects
				(font
					(size 1.27 1.27)
					(thickness 0.15)
				)
				(justify left bottom)
				(hide yes)
			)
		)
		(property "Val" "0R"
			(at 247.65 226.06 0)
			(effects
				(font
					(size 1.27 1.27)
					(thickness 0.15)
				)
			)
		)
		(property "Tolerance" "~"
			(at 233.68 237.49 0)
			(effects
				(font
					(size 1.27 1.27)
				)
				(justify left bottom)
				(hide yes)
			)
		)
		(property "Current" "1A"
			(at 233.68 257.81 0)
			(effects
				(font
					(size 1.27 1.27)
					(thickness 0.15)
				)
				(justify left bottom)
				(hide yes)
			)
		)
		(property "Public" "False"
			(at 233.68 257.81 0)
			(effects
				(font
					(size 1.27 1.27)
				)
				(justify left bottom)
				(hide yes)
			)
		)
		(pin "1"
		)
		(pin "2"
		)
		(instances
			(project "com-express-7-baseboard"
				(path ""
					(reference "R28")
					(unit 1)
				)
			)
		)
	)
	(symbol
		(lib_id "antmicroResistors0402:R_0R_0402")
		(at 254 157.48 0)
		(mirror y)
		(unit 1)
		(exclude_from_sim no)
		(in_bom yes)
		(on_board yes)
		(dnp no)
		(property "Reference" "R26"
			(at 256.54 156.21 0)
			(effects
				(font
					(size 1.27 1.27)
					(thickness 0.15)
				)
			)
		)
		(property "Value" "R_0R_0402"
			(at 233.68 170.18 0)
			(effects
				(font
					(size 1.27 1.27)
					(thickness 0.15)
				)
				(justify left bottom)
				(hide yes)
			)
		)
		(property "Footprint" "antmicro-footprints:R_0402_1005Metric"
			(at 233.68 172.72 0)
			(effects
				(font
					(size 1.27 1.27)
					(thickness 0.15)
				)
				(justify left bottom)
				(hide yes)
			)
		)
		(property "Datasheet" "https://industrial.panasonic.com/cdbs/www-data/pdf/RDA0000/AOA0000C301.pdf"
			(at 233.68 175.26 0)
			(effects
				(font
					(size 1.27 1.27)
					(thickness 0.15)
				)
				(justify left bottom)
				(hide yes)
			)
		)
		(property "Description" ""
			(at 254 157.48 0)
			(effects
				(font
					(size 1.27 1.27)
				)
				(hide yes)
			)
		)
		(property "MPN" "ERJ2GE0R00X"
			(at 233.68 177.8 0)
			(effects
				(font
					(size 1.27 1.27)
					(thickness 0.15)
				)
				(justify left bottom)
				(hide yes)
			)
		)
		(property "Manufacturer" "Panasonic"
			(at 233.68 180.34 0)
			(effects
				(font
					(size 1.27 1.27)
					(thickness 0.15)
				)
				(justify left bottom)
				(hide yes)
			)
		)
		(property "License" "Apache-2.0"
			(at 233.68 182.88 0)
			(effects
				(font
					(size 1.27 1.27)
					(thickness 0.15)
				)
				(justify left bottom)
				(hide yes)
			)
		)
		(property "Author" "Antmicro"
			(at 233.68 185.42 0)
			(effects
				(font
					(size 1.27 1.27)
					(thickness 0.15)
				)
				(justify left bottom)
				(hide yes)
			)
		)
		(property "Val" "0R"
			(at 247.65 156.21 0)
			(effects
				(font
					(size 1.27 1.27)
					(thickness 0.15)
				)
			)
		)
		(property "Tolerance" "~"
			(at 233.68 167.64 0)
			(effects
				(font
					(size 1.27 1.27)
				)
				(justify left bottom)
				(hide yes)
			)
		)
		(property "Current" "1A"
			(at 233.68 187.96 0)
			(effects
				(font
					(size 1.27 1.27)
					(thickness 0.15)
				)
				(justify left bottom)
				(hide yes)
			)
		)
		(property "Public" "False"
			(at 233.68 187.96 0)
			(effects
				(font
					(size 1.27 1.27)
				)
				(justify left bottom)
				(hide yes)
			)
		)
		(pin "1"
		)
		(pin "2"
		)
		(instances
			(project "com-express-7-baseboard"
				(path ""
					(reference "R26")
					(unit 1)
				)
			)
		)
	)
	(symbol
		(lib_id "antmicroCapacitors0603:C_22u_16V_0603")
		(at 280.67 219.71 90)
		(unit 1)
		(exclude_from_sim no)
		(in_bom yes)
		(on_board yes)
		(dnp no)
		(fields_autoplaced yes)
		(property "Reference" "C20"
			(at 283.21 215.8935 90)
			(effects
				(font
					(size 1.27 1.27)
					(thickness 0.15)
				)
				(justify right)
			)
		)
		(property "Value" "C_22u_16V_0603"
			(at 290.83 199.39 0)
			(effects
				(font
					(size 1.27 1.27)
					(thickness 0.15)
				)
				(justify left bottom)
				(hide yes)
			)
		)
		(property "Footprint" "antmicro-footprints:C_0603_1608Metric"
			(at 293.37 199.39 0)
			(effects
				(font
					(size 1.27 1.27)
					(thickness 0.15)
				)
				(justify left bottom)
				(hide yes)
			)
		)
		(property "Datasheet" "https://product.samsungsem.com/mlcc/CL10A226MO7JZN.do"
			(at 295.91 199.39 0)
			(effects
				(font
					(size 1.27 1.27)
					(thickness 0.15)
				)
				(justify left bottom)
				(hide yes)
			)
		)
		(property "Description" ""
			(at 280.67 219.71 0)
			(effects
				(font
					(size 1.27 1.27)
				)
				(hide yes)
			)
		)
		(property "MPN" "CL10A226MO7JZNC"
			(at 298.45 199.39 0)
			(effects
				(font
					(size 1.27 1.27)
					(thickness 0.15)
				)
				(justify left bottom)
				(hide yes)
			)
		)
		(property "Manufacturer" "Samsung Electro-Mechanics"
			(at 300.99 199.39 0)
			(effects
				(font
					(size 1.27 1.27)
					(thickness 0.15)
				)
				(justify left bottom)
				(hide yes)
			)
		)
		(property "License" "Apache-2.0"
			(at 303.53 199.39 0)
			(effects
				(font
					(size 1.27 1.27)
					(thickness 0.15)
				)
				(justify left bottom)
				(hide yes)
			)
		)
		(property "Author" "Antmicro"
			(at 306.07 199.39 0)
			(effects
				(font
					(size 1.27 1.27)
					(thickness 0.15)
				)
				(justify left bottom)
				(hide yes)
			)
		)
		(property "Val" "22u"
			(at 283.21 218.4335 90)
			(effects
				(font
					(size 1.27 1.27)
					(thickness 0.15)
				)
				(justify right)
			)
		)
		(property "Voltage" "16V"
			(at 308.61 199.39 0)
			(effects
				(font
					(size 1.27 1.27)
				)
				(justify left bottom)
				(hide yes)
			)
		)
		(property "Dielectric" ""
			(at 311.15 199.39 0)
			(effects
				(font
					(size 1.27 1.27)
				)
				(justify left bottom)
				(hide yes)
			)
		)
		(property "Public" "False"
			(at 313.69 199.39 0)
			(effects
				(font
					(size 1.27 1.27)
				)
				(justify left bottom)
				(hide yes)
			)
		)
		(pin "2"
		)
		(pin "1"
		)
		(instances
			(project "com-express-7-baseboard"
				(path ""
					(reference "C20")
					(unit 1)
				)
			)
		)
	)
	(symbol
		(lib_id "antmicropower:GND")
		(at 163.83 107.95 0)
		(mirror y)
		(unit 1)
		(exclude_from_sim no)
		(in_bom yes)
		(on_board yes)
		(dnp no)
		(property "Reference" "#PWR09"
			(at 154.94 110.49 0)
			(effects
				(font
					(size 1.27 1.27)
					(thickness 0.15)
				)
				(justify left bottom)
				(hide yes)
			)
		)
		(property "Value" "GND"
			(at 163.83 111.76 0)
			(effects
				(font
					(size 1.27 1.27)
					(thickness 0.15)
				)
			)
		)
		(property "Footprint" ""
			(at 154.94 115.57 0)
			(effects
				(font
					(size 1.27 1.27)
					(thickness 0.15)
				)
				(justify left bottom)
				(hide yes)
			)
		)
		(property "Datasheet" ""
			(at 154.94 120.65 0)
			(effects
				(font
					(size 1.27 1.27)
					(thickness 0.15)
				)
				(justify left bottom)
				(hide yes)
			)
		)
		(property "Description" ""
			(at 163.83 107.95 0)
			(effects
				(font
					(size 1.27 1.27)
				)
				(hide yes)
			)
		)
		(property "Author" "Antmicro"
			(at 154.94 115.57 0)
			(effects
				(font
					(size 1.27 1.27)
					(thickness 0.15)
				)
				(justify left bottom)
				(hide yes)
			)
		)
		(property "License" "Apache-2.0"
			(at 154.94 118.11 0)
			(effects
				(font
					(size 1.27 1.27)
					(thickness 0.15)
				)
				(justify left bottom)
				(hide yes)
			)
		)
		(pin "1"
		)
		(instances
			(project "com-express-7-baseboard"
				(path ""
					(reference "#PWR09")
					(unit 1)
				)
			)
		)
	)
	(symbol
		(lib_id "antmicroPMICPowerDistributionSwitchesLoadDrivers:AP22615A_TSOT26")
		(at 223.52 224.79 0)
		(mirror y)
		(unit 1)
		(exclude_from_sim no)
		(in_bom yes)
		(on_board yes)
		(dnp no)
		(property "Reference" "U4"
			(at 217.17 218.44 0)
			(effects
				(font
					(size 1.27 1.27)
				)
				(justify left bottom)
			)
		)
		(property "Value" "AP22615A_TSOT26"
			(at 222.25 222.25 0)
			(effects
				(font
					(size 1.27 1.27)
					(thickness 0.15)
				)
				(justify left bottom)
				(hide yes)
			)
		)
		(property "Footprint" "antmicro-footprints:TSOT23-6"
			(at 193.04 232.41 0)
			(effects
				(font
					(size 1.27 1.27)
					(thickness 0.15)
				)
				(justify left bottom)
				(hide yes)
			)
		)
		(property "Datasheet" "https://www.mouser.com/datasheet/2/115/DIOD_S_A0008958405_1-2543193.pdf"
			(at 193.04 234.95 0)
			(effects
				(font
					(size 1.27 1.27)
					(thickness 0.15)
				)
				(justify left bottom)
				(hide yes)
			)
		)
		(property "Description" ""
			(at 223.52 224.79 0)
			(effects
				(font
					(size 1.27 1.27)
				)
				(hide yes)
			)
		)
		(property "MPN" "AP22615AWU-7"
			(at 223.52 220.98 0)
			(effects
				(font
					(size 1.27 1.27)
					(thickness 0.15)
				)
				(justify left bottom)
			)
		)
		(property "Manufacturer" "Diodes Incorporated"
			(at 193.04 240.03 0)
			(effects
				(font
					(size 1.27 1.27)
					(thickness 0.15)
				)
				(justify left bottom)
				(hide yes)
			)
		)
		(property "Author" "Antmicro"
			(at 193.04 242.57 0)
			(effects
				(font
					(size 1.27 1.27)
					(thickness 0.15)
				)
				(justify left bottom)
				(hide yes)
			)
		)
		(property "License" "Apache-2.0"
			(at 193.04 245.11 0)
			(effects
				(font
					(size 1.27 1.27)
					(thickness 0.15)
				)
				(justify left bottom)
				(hide yes)
			)
		)
		(pin "1"
		)
		(pin "2"
		)
		(pin "3"
		)
		(pin "4"
		)
		(pin "5"
		)
		(pin "6"
		)
		(instances
			(project "com-express-7-baseboard"
				(path ""
					(reference "U4")
					(unit 1)
				)
			)
		)
	)
	(symbol
		(lib_id "antmicroPMICPowerDistributionSwitchesLoadDrivers:AP22615A_TSOT26")
		(at 223.52 154.94 0)
		(mirror y)
		(unit 1)
		(exclude_from_sim no)
		(in_bom yes)
		(on_board yes)
		(dnp no)
		(property "Reference" "U3"
			(at 217.17 148.59 0)
			(effects
				(font
					(size 1.27 1.27)
				)
				(justify left bottom)
			)
		)
		(property "Value" "AP22615A_TSOT26"
			(at 222.25 152.4 0)
			(effects
				(font
					(size 1.27 1.27)
					(thickness 0.15)
				)
				(justify left bottom)
				(hide yes)
			)
		)
		(property "Footprint" "antmicro-footprints:TSOT23-6"
			(at 193.04 162.56 0)
			(effects
				(font
					(size 1.27 1.27)
					(thickness 0.15)
				)
				(justify left bottom)
				(hide yes)
			)
		)
		(property "Datasheet" "https://www.mouser.com/datasheet/2/115/DIOD_S_A0008958405_1-2543193.pdf"
			(at 193.04 165.1 0)
			(effects
				(font
					(size 1.27 1.27)
					(thickness 0.15)
				)
				(justify left bottom)
				(hide yes)
			)
		)
		(property "Description" ""
			(at 223.52 154.94 0)
			(effects
				(font
					(size 1.27 1.27)
				)
				(hide yes)
			)
		)
		(property "MPN" "AP22615AWU-7"
			(at 223.52 151.13 0)
			(effects
				(font
					(size 1.27 1.27)
					(thickness 0.15)
				)
				(justify left bottom)
			)
		)
		(property "Manufacturer" "Diodes Incorporated"
			(at 193.04 170.18 0)
			(effects
				(font
					(size 1.27 1.27)
					(thickness 0.15)
				)
				(justify left bottom)
				(hide yes)
			)
		)
		(property "Author" "Antmicro"
			(at 193.04 172.72 0)
			(effects
				(font
					(size 1.27 1.27)
					(thickness 0.15)
				)
				(justify left bottom)
				(hide yes)
			)
		)
		(property "License" "Apache-2.0"
			(at 193.04 175.26 0)
			(effects
				(font
					(size 1.27 1.27)
					(thickness 0.15)
				)
				(justify left bottom)
				(hide yes)
			)
		)
		(pin "1"
		)
		(pin "2"
		)
		(pin "3"
		)
		(pin "4"
		)
		(pin "5"
		)
		(pin "6"
		)
		(instances
			(project "com-express-7-baseboard"
				(path ""
					(reference "U3")
					(unit 1)
				)
			)
		)
	)
	(symbol
		(lib_id "antmicropower:GND")
		(at 274.32 106.68 0)
		(mirror y)
		(unit 1)
		(exclude_from_sim no)
		(in_bom yes)
		(on_board yes)
		(dnp no)
		(property "Reference" "#PWR027"
			(at 265.43 109.22 0)
			(effects
				(font
					(size 1.27 1.27)
					(thickness 0.15)
				)
				(justify left bottom)
				(hide yes)
			)
		)
		(property "Value" "GND"
			(at 274.32 110.49 0)
			(effects
				(font
					(size 1.27 1.27)
					(thickness 0.15)
				)
			)
		)
		(property "Footprint" ""
			(at 265.43 114.3 0)
			(effects
				(font
					(size 1.27 1.27)
					(thickness 0.15)
				)
				(justify left bottom)
				(hide yes)
			)
		)
		(property "Datasheet" ""
			(at 265.43 119.38 0)
			(effects
				(font
					(size 1.27 1.27)
					(thickness 0.15)
				)
				(justify left bottom)
				(hide yes)
			)
		)
		(property "Description" ""
			(at 274.32 106.68 0)
			(effects
				(font
					(size 1.27 1.27)
				)
				(hide yes)
			)
		)
		(property "Author" "Antmicro"
			(at 265.43 114.3 0)
			(effects
				(font
					(size 1.27 1.27)
					(thickness 0.15)
				)
				(justify left bottom)
				(hide yes)
			)
		)
		(property "License" "Apache-2.0"
			(at 265.43 116.84 0)
			(effects
				(font
					(size 1.27 1.27)
					(thickness 0.15)
				)
				(justify left bottom)
				(hide yes)
			)
		)
		(pin "1"
		)
		(instances
			(project "com-express-7-baseboard"
				(path ""
					(reference "#PWR027")
					(unit 1)
				)
			)
		)
	)
	(symbol
		(lib_id "antmicroInterfaceDriversReceiversTransceivers:Trans_SM453229-381N7Y")
		(at 245.11 91.44 0)
		(unit 1)
		(exclude_from_sim no)
		(in_bom yes)
		(on_board yes)
		(dnp no)
		(fields_autoplaced yes)
		(property "Reference" "T8"
			(at 250.19 86.36 0)
			(effects
				(font
					(size 1.27 1.27)
					(thickness 0.15)
				)
			)
		)
		(property "Value" "Trans_SM453229-381N7Y"
			(at 271.78 104.14 0)
			(effects
				(font
					(size 1.27 1.27)
					(thickness 0.15)
				)
				(justify left bottom)
				(hide yes)
			)
		)
		(property "Footprint" "antmicro-footprints:Trans_Eth_4.7x3.3mm"
			(at 271.78 106.68 0)
			(effects
				(font
					(size 1.27 1.27)
					(thickness 0.15)
				)
				(justify left bottom)
				(hide yes)
			)
		)
		(property "Datasheet" "https://eu.mouser.com/datasheet/2/54/bourns_02132019_SM453229-381N7Y_datasheet-1532071.pdf"
			(at 271.78 109.22 0)
			(effects
				(font
					(size 1.27 1.27)
					(thickness 0.15)
				)
				(justify left bottom)
				(hide yes)
			)
		)
		(property "Description" ""
			(at 245.11 91.44 0)
			(effects
				(font
					(size 1.27 1.27)
				)
				(hide yes)
			)
		)
		(property "MPN" "SM453229-381N7Y"
			(at 250.19 88.9 0)
			(effects
				(font
					(size 1.27 1.27)
					(thickness 0.15)
				)
			)
		)
		(property "Manufacturer" "Bourns"
			(at 271.78 101.6 0)
			(effects
				(font
					(size 1.27 1.27)
					(thickness 0.15)
				)
				(justify left bottom)
				(hide yes)
			)
		)
		(property "Author" "Antmicro"
			(at 271.78 111.76 0)
			(effects
				(font
					(size 1.27 1.27)
					(thickness 0.15)
				)
				(justify left bottom)
				(hide yes)
			)
		)
		(property "License" "Apache-2.0"
			(at 271.78 114.3 0)
			(effects
				(font
					(size 1.27 1.27)
					(thickness 0.15)
				)
				(justify left bottom)
				(hide yes)
			)
		)
		(pin "7"
		)
		(pin "3"
		)
		(pin "1"
		)
		(pin "5"
		)
		(pin "2"
		)
		(pin "6"
		)
		(instances
			(project "com-express-7-baseboard"
				(path ""
					(reference "T8")
					(unit 1)
				)
			)
		)
	)
	(symbol
		(lib_id "antmicropower:GND")
		(at 182.88 233.68 0)
		(mirror y)
		(unit 1)
		(exclude_from_sim no)
		(in_bom yes)
		(on_board yes)
		(dnp no)
		(property "Reference" "#PWR011"
			(at 173.99 236.22 0)
			(effects
				(font
					(size 1.27 1.27)
					(thickness 0.15)
				)
				(justify left bottom)
				(hide yes)
			)
		)
		(property "Value" "GND"
			(at 182.88 237.49 0)
			(effects
				(font
					(size 1.27 1.27)
					(thickness 0.15)
				)
			)
		)
		(property "Footprint" ""
			(at 173.99 241.3 0)
			(effects
				(font
					(size 1.27 1.27)
					(thickness 0.15)
				)
				(justify left bottom)
				(hide yes)
			)
		)
		(property "Datasheet" ""
			(at 173.99 246.38 0)
			(effects
				(font
					(size 1.27 1.27)
					(thickness 0.15)
				)
				(justify left bottom)
				(hide yes)
			)
		)
		(property "Description" ""
			(at 182.88 233.68 0)
			(effects
				(font
					(size 1.27 1.27)
				)
				(hide yes)
			)
		)
		(property "Author" "Antmicro"
			(at 173.99 241.3 0)
			(effects
				(font
					(size 1.27 1.27)
					(thickness 0.15)
				)
				(justify left bottom)
				(hide yes)
			)
		)
		(property "License" "Apache-2.0"
			(at 173.99 243.84 0)
			(effects
				(font
					(size 1.27 1.27)
					(thickness 0.15)
				)
				(justify left bottom)
				(hide yes)
			)
		)
		(pin "1"
		)
		(instances
			(project "com-express-7-baseboard"
				(path ""
					(reference "#PWR011")
					(unit 1)
				)
			)
		)
	)
	(symbol
		(lib_id "antmicroResistors0402:R_0R_0402")
		(at 93.98 90.17 0)
		(unit 1)
		(exclude_from_sim no)
		(in_bom yes)
		(on_board yes)
		(dnp no)
		(property "Reference" "R5"
			(at 92.71 88.9 0)
			(effects
				(font
					(size 1.27 1.27)
					(thickness 0.15)
				)
			)
		)
		(property "Value" "R_0R_0402"
			(at 114.3 102.87 0)
			(effects
				(font
					(size 1.27 1.27)
					(thickness 0.15)
				)
				(justify left bottom)
				(hide yes)
			)
		)
		(property "Footprint" "antmicro-footprints:R_0402_1005Metric"
			(at 114.3 105.41 0)
			(effects
				(font
					(size 1.27 1.27)
					(thickness 0.15)
				)
				(justify left bottom)
				(hide yes)
			)
		)
		(property "Datasheet" "https://industrial.panasonic.com/cdbs/www-data/pdf/RDA0000/AOA0000C301.pdf"
			(at 114.3 107.95 0)
			(effects
				(font
					(size 1.27 1.27)
					(thickness 0.15)
				)
				(justify left bottom)
				(hide yes)
			)
		)
		(property "Description" ""
			(at 93.98 90.17 0)
			(effects
				(font
					(size 1.27 1.27)
				)
				(hide yes)
			)
		)
		(property "MPN" "ERJ2GE0R00X"
			(at 114.3 110.49 0)
			(effects
				(font
					(size 1.27 1.27)
					(thickness 0.15)
				)
				(justify left bottom)
				(hide yes)
			)
		)
		(property "Manufacturer" "Panasonic"
			(at 114.3 113.03 0)
			(effects
				(font
					(size 1.27 1.27)
					(thickness 0.15)
				)
				(justify left bottom)
				(hide yes)
			)
		)
		(property "License" "Apache-2.0"
			(at 114.3 115.57 0)
			(effects
				(font
					(size 1.27 1.27)
					(thickness 0.15)
				)
				(justify left bottom)
				(hide yes)
			)
		)
		(property "Author" "Antmicro"
			(at 114.3 118.11 0)
			(effects
				(font
					(size 1.27 1.27)
					(thickness 0.15)
				)
				(justify left bottom)
				(hide yes)
			)
		)
		(property "Val" "0R"
			(at 100.33 88.9 0)
			(effects
				(font
					(size 1.27 1.27)
					(thickness 0.15)
				)
			)
		)
		(property "Tolerance" "~"
			(at 114.3 100.33 0)
			(effects
				(font
					(size 1.27 1.27)
				)
				(justify left bottom)
				(hide yes)
			)
		)
		(property "Current" "1A"
			(at 114.3 120.65 0)
			(effects
				(font
					(size 1.27 1.27)
					(thickness 0.15)
				)
				(justify left bottom)
				(hide yes)
			)
		)
		(property "Public" "False"
			(at 114.3 120.65 0)
			(effects
				(font
					(size 1.27 1.27)
				)
				(justify left bottom)
				(hide yes)
			)
		)
		(pin "1"
		)
		(pin "2"
		)
		(instances
			(project "com-express-7-baseboard"
				(path ""
					(reference "R5")
					(unit 1)
				)
			)
		)
	)
	(symbol
		(lib_id "antmicroResistors0402:R_470R_0402")
		(at 118.11 81.28 90)
		(unit 1)
		(exclude_from_sim no)
		(in_bom yes)
		(on_board yes)
		(dnp yes)
		(property "Reference" "R10"
			(at 119.38 77.47 90)
			(effects
				(font
					(size 1.27 1.27)
					(thickness 0.15)
				)
				(justify right)
			)
		)
		(property "Value" "R_470R_0402"
			(at 130.81 60.96 0)
			(effects
				(font
					(size 1.27 1.27)
					(thickness 0.15)
				)
				(justify left bottom)
				(hide yes)
			)
		)
		(property "Footprint" "antmicro-footprints:R_0402_1005Metric"
			(at 133.35 60.96 0)
			(effects
				(font
					(size 1.27 1.27)
					(thickness 0.15)
				)
				(justify left bottom)
				(hide yes)
			)
		)
		(property "Datasheet" "https://www.bourns.com/docs/product-datasheets/cr.pdf"
			(at 135.89 60.96 0)
			(effects
				(font
					(size 1.27 1.27)
					(thickness 0.15)
				)
				(justify left bottom)
				(hide yes)
			)
		)
		(property "Description" ""
			(at 118.11 81.28 0)
			(effects
				(font
					(size 1.27 1.27)
				)
				(hide yes)
			)
		)
		(property "MPN" "CR0402-FX-4700GLF"
			(at 138.43 60.96 0)
			(effects
				(font
					(size 1.27 1.27)
					(thickness 0.15)
				)
				(justify left bottom)
				(hide yes)
			)
		)
		(property "Manufacturer" "Bourns"
			(at 140.97 60.96 0)
			(effects
				(font
					(size 1.27 1.27)
					(thickness 0.15)
				)
				(justify left bottom)
				(hide yes)
			)
		)
		(property "License" "Apache-2.0"
			(at 143.51 60.96 0)
			(effects
				(font
					(size 1.27 1.27)
					(thickness 0.15)
				)
				(justify left bottom)
				(hide yes)
			)
		)
		(property "Author" "Antmicro"
			(at 146.05 60.96 0)
			(effects
				(font
					(size 1.27 1.27)
					(thickness 0.15)
				)
				(justify left bottom)
				(hide yes)
			)
		)
		(property "Val" "470R"
			(at 119.38 80.01 90)
			(effects
				(font
					(size 1.27 1.27)
					(thickness 0.15)
				)
				(justify right)
			)
		)
		(property "Tolerance" "1%"
			(at 128.27 60.96 0)
			(effects
				(font
					(size 1.27 1.27)
				)
				(justify left bottom)
				(hide yes)
			)
		)
		(property "Public" "False"
			(at 148.59 60.96 0)
			(effects
				(font
					(size 1.27 1.27)
				)
				(justify left bottom)
				(hide yes)
			)
		)
		(pin "2"
		)
		(pin "1"
		)
		(instances
			(project "com-express-7-baseboard"
				(path ""
					(reference "R10")
					(unit 1)
				)
			)
		)
	)
	(symbol
		(lib_id "antmicroResistors0402:R_10k_0402")
		(at 233.68 226.06 270)
		(mirror x)
		(unit 1)
		(exclude_from_sim no)
		(in_bom yes)
		(on_board yes)
		(dnp yes)
		(property "Reference" "R19"
			(at 232.41 222.25 90)
			(effects
				(font
					(size 1.27 1.27)
					(thickness 0.15)
				)
				(justify right)
			)
		)
		(property "Value" "R_10k_0402"
			(at 220.98 205.74 0)
			(effects
				(font
					(size 1.27 1.27)
					(thickness 0.15)
				)
				(justify left bottom)
				(hide yes)
			)
		)
		(property "Footprint" "antmicro-footprints:R_0402_1005Metric"
			(at 218.44 205.74 0)
			(effects
				(font
					(size 1.27 1.27)
					(thickness 0.15)
				)
				(justify left bottom)
				(hide yes)
			)
		)
		(property "Datasheet" "https://www.bourns.com/docs/product-datasheets/cr.pdf"
			(at 215.9 205.74 0)
			(effects
				(font
					(size 1.27 1.27)
					(thickness 0.15)
				)
				(justify left bottom)
				(hide yes)
			)
		)
		(property "Description" ""
			(at 233.68 226.06 0)
			(effects
				(font
					(size 1.27 1.27)
				)
				(hide yes)
			)
		)
		(property "MPN" "CR0402-FX-1002GLF"
			(at 213.36 205.74 0)
			(effects
				(font
					(size 1.27 1.27)
					(thickness 0.15)
				)
				(justify left bottom)
				(hide yes)
			)
		)
		(property "Manufacturer" "Bourns"
			(at 210.82 205.74 0)
			(effects
				(font
					(size 1.27 1.27)
					(thickness 0.15)
				)
				(justify left bottom)
				(hide yes)
			)
		)
		(property "License" "Apache-2.0"
			(at 208.28 205.74 0)
			(effects
				(font
					(size 1.27 1.27)
					(thickness 0.15)
				)
				(justify left bottom)
				(hide yes)
			)
		)
		(property "Author" "Antmicro"
			(at 205.74 205.74 0)
			(effects
				(font
					(size 1.27 1.27)
					(thickness 0.15)
				)
				(justify left bottom)
				(hide yes)
			)
		)
		(property "Val" "10k"
			(at 232.41 224.79 90)
			(effects
				(font
					(size 1.27 1.27)
					(thickness 0.15)
				)
				(justify right)
			)
		)
		(property "Tolerance" "1%"
			(at 223.52 205.74 0)
			(effects
				(font
					(size 1.27 1.27)
				)
				(justify left bottom)
				(hide yes)
			)
		)
		(property "Public" "False"
			(at 203.2 205.74 0)
			(effects
				(font
					(size 1.27 1.27)
				)
				(justify left bottom)
				(hide yes)
			)
		)
		(pin "1"
		)
		(pin "2"
		)
		(instances
			(project "com-express-7-baseboard"
				(path ""
					(reference "R19")
					(unit 1)
				)
			)
		)
	)
	(symbol
		(lib_id "antmicroResistors0402:R_0R_0402")
		(at 93.98 66.04 0)
		(unit 1)
		(exclude_from_sim no)
		(in_bom yes)
		(on_board yes)
		(dnp yes)
		(property "Reference" "R2"
			(at 92.71 67.31 0)
			(effects
				(font
					(size 1.27 1.27)
					(thickness 0.15)
				)
			)
		)
		(property "Value" "R_0R_0402"
			(at 114.3 78.74 0)
			(effects
				(font
					(size 1.27 1.27)
					(thickness 0.15)
				)
				(justify left bottom)
				(hide yes)
			)
		)
		(property "Footprint" "antmicro-footprints:R_0402_1005Metric"
			(at 114.3 81.28 0)
			(effects
				(font
					(size 1.27 1.27)
					(thickness 0.15)
				)
				(justify left bottom)
				(hide yes)
			)
		)
		(property "Datasheet" "https://industrial.panasonic.com/cdbs/www-data/pdf/RDA0000/AOA0000C301.pdf"
			(at 114.3 83.82 0)
			(effects
				(font
					(size 1.27 1.27)
					(thickness 0.15)
				)
				(justify left bottom)
				(hide yes)
			)
		)
		(property "Description" ""
			(at 93.98 66.04 0)
			(effects
				(font
					(size 1.27 1.27)
				)
				(hide yes)
			)
		)
		(property "MPN" "ERJ2GE0R00X"
			(at 114.3 86.36 0)
			(effects
				(font
					(size 1.27 1.27)
					(thickness 0.15)
				)
				(justify left bottom)
				(hide yes)
			)
		)
		(property "Manufacturer" "Panasonic"
			(at 114.3 88.9 0)
			(effects
				(font
					(size 1.27 1.27)
					(thickness 0.15)
				)
				(justify left bottom)
				(hide yes)
			)
		)
		(property "License" "Apache-2.0"
			(at 114.3 91.44 0)
			(effects
				(font
					(size 1.27 1.27)
					(thickness 0.15)
				)
				(justify left bottom)
				(hide yes)
			)
		)
		(property "Author" "Antmicro"
			(at 114.3 93.98 0)
			(effects
				(font
					(size 1.27 1.27)
					(thickness 0.15)
				)
				(justify left bottom)
				(hide yes)
			)
		)
		(property "Val" "0R"
			(at 100.33 67.31 0)
			(effects
				(font
					(size 1.27 1.27)
					(thickness 0.15)
				)
			)
		)
		(property "Tolerance" "~"
			(at 114.3 76.2 0)
			(effects
				(font
					(size 1.27 1.27)
				)
				(justify left bottom)
				(hide yes)
			)
		)
		(property "Current" "1A"
			(at 114.3 96.52 0)
			(effects
				(font
					(size 1.27 1.27)
					(thickness 0.15)
				)
				(justify left bottom)
				(hide yes)
			)
		)
		(property "Public" "False"
			(at 114.3 96.52 0)
			(effects
				(font
					(size 1.27 1.27)
				)
				(justify left bottom)
				(hide yes)
			)
		)
		(pin "1"
		)
		(pin "2"
		)
		(instances
			(project "com-express-7-baseboard"
				(path ""
					(reference "R2")
					(unit 1)
				)
			)
		)
	)
	(symbol
		(lib_id "antmicroResistors0402:R_470R_0402")
		(at 110.49 81.28 90)
		(unit 1)
		(exclude_from_sim no)
		(in_bom yes)
		(on_board yes)
		(dnp no)
		(property "Reference" "R8"
			(at 111.76 77.47 90)
			(effects
				(font
					(size 1.27 1.27)
					(thickness 0.15)
				)
				(justify right)
			)
		)
		(property "Value" "R_470R_0402"
			(at 123.19 60.96 0)
			(effects
				(font
					(size 1.27 1.27)
					(thickness 0.15)
				)
				(justify left bottom)
				(hide yes)
			)
		)
		(property "Footprint" "antmicro-footprints:R_0402_1005Metric"
			(at 125.73 60.96 0)
			(effects
				(font
					(size 1.27 1.27)
					(thickness 0.15)
				)
				(justify left bottom)
				(hide yes)
			)
		)
		(property "Datasheet" "https://www.bourns.com/docs/product-datasheets/cr.pdf"
			(at 128.27 60.96 0)
			(effects
				(font
					(size 1.27 1.27)
					(thickness 0.15)
				)
				(justify left bottom)
				(hide yes)
			)
		)
		(property "Description" ""
			(at 110.49 81.28 0)
			(effects
				(font
					(size 1.27 1.27)
				)
				(hide yes)
			)
		)
		(property "MPN" "CR0402-FX-4700GLF"
			(at 130.81 60.96 0)
			(effects
				(font
					(size 1.27 1.27)
					(thickness 0.15)
				)
				(justify left bottom)
				(hide yes)
			)
		)
		(property "Manufacturer" "Bourns"
			(at 133.35 60.96 0)
			(effects
				(font
					(size 1.27 1.27)
					(thickness 0.15)
				)
				(justify left bottom)
				(hide yes)
			)
		)
		(property "License" "Apache-2.0"
			(at 135.89 60.96 0)
			(effects
				(font
					(size 1.27 1.27)
					(thickness 0.15)
				)
				(justify left bottom)
				(hide yes)
			)
		)
		(property "Author" "Antmicro"
			(at 138.43 60.96 0)
			(effects
				(font
					(size 1.27 1.27)
					(thickness 0.15)
				)
				(justify left bottom)
				(hide yes)
			)
		)
		(property "Val" "470R"
			(at 111.76 80.01 90)
			(effects
				(font
					(size 1.27 1.27)
					(thickness 0.15)
				)
				(justify right)
			)
		)
		(property "Tolerance" "1%"
			(at 120.65 60.96 0)
			(effects
				(font
					(size 1.27 1.27)
				)
				(justify left bottom)
				(hide yes)
			)
		)
		(property "Public" "False"
			(at 140.97 60.96 0)
			(effects
				(font
					(size 1.27 1.27)
				)
				(justify left bottom)
				(hide yes)
			)
		)
		(pin "2"
		)
		(pin "1"
		)
		(instances
			(project "com-express-7-baseboard"
				(path ""
					(reference "R8")
					(unit 1)
				)
			)
		)
	)
	(symbol
		(lib_id "antmicroResistors0402:R_0R_0402")
		(at 238.76 241.3 0)
		(mirror y)
		(unit 1)
		(exclude_from_sim no)
		(in_bom yes)
		(on_board yes)
		(dnp no)
		(property "Reference" "R22"
			(at 232.41 240.03 0)
			(effects
				(font
					(size 1.27 1.27)
					(thickness 0.15)
				)
			)
		)
		(property "Value" "R_0R_0402"
			(at 218.44 254 0)
			(effects
				(font
					(size 1.27 1.27)
					(thickness 0.15)
				)
				(justify left bottom)
				(hide yes)
			)
		)
		(property "Footprint" "antmicro-footprints:R_0402_1005Metric"
			(at 218.44 256.54 0)
			(effects
				(font
					(size 1.27 1.27)
					(thickness 0.15)
				)
				(justify left bottom)
				(hide yes)
			)
		)
		(property "Datasheet" "https://industrial.panasonic.com/cdbs/www-data/pdf/RDA0000/AOA0000C301.pdf"
			(at 218.44 259.08 0)
			(effects
				(font
					(size 1.27 1.27)
					(thickness 0.15)
				)
				(justify left bottom)
				(hide yes)
			)
		)
		(property "Description" ""
			(at 238.76 241.3 0)
			(effects
				(font
					(size 1.27 1.27)
				)
				(hide yes)
			)
		)
		(property "MPN" "ERJ2GE0R00X"
			(at 218.44 261.62 0)
			(effects
				(font
					(size 1.27 1.27)
					(thickness 0.15)
				)
				(justify left bottom)
				(hide yes)
			)
		)
		(property "Manufacturer" "Panasonic"
			(at 218.44 264.16 0)
			(effects
				(font
					(size 1.27 1.27)
					(thickness 0.15)
				)
				(justify left bottom)
				(hide yes)
			)
		)
		(property "License" "Apache-2.0"
			(at 218.44 266.7 0)
			(effects
				(font
					(size 1.27 1.27)
					(thickness 0.15)
				)
				(justify left bottom)
				(hide yes)
			)
		)
		(property "Author" "Antmicro"
			(at 218.44 269.24 0)
			(effects
				(font
					(size 1.27 1.27)
					(thickness 0.15)
				)
				(justify left bottom)
				(hide yes)
			)
		)
		(property "Val" "0R"
			(at 240.03 240.03 0)
			(effects
				(font
					(size 1.27 1.27)
					(thickness 0.15)
				)
			)
		)
		(property "Tolerance" "~"
			(at 218.44 251.46 0)
			(effects
				(font
					(size 1.27 1.27)
				)
				(justify left bottom)
				(hide yes)
			)
		)
		(property "Current" "1A"
			(at 218.44 271.78 0)
			(effects
				(font
					(size 1.27 1.27)
					(thickness 0.15)
				)
				(justify left bottom)
				(hide yes)
			)
		)
		(property "Public" "False"
			(at 218.44 271.78 0)
			(effects
				(font
					(size 1.27 1.27)
				)
				(justify left bottom)
				(hide yes)
			)
		)
		(pin "1"
		)
		(pin "2"
		)
		(instances
			(project "com-express-7-baseboard"
				(path ""
					(reference "R22")
					(unit 1)
				)
			)
		)
	)
	(symbol
		(lib_id "antmicropower:GND")
		(at 137.16 260.35 0)
		(mirror y)
		(unit 1)
		(exclude_from_sim no)
		(in_bom yes)
		(on_board yes)
		(dnp no)
		(property "Reference" "#PWR04"
			(at 128.27 262.89 0)
			(effects
				(font
					(size 1.27 1.27)
					(thickness 0.15)
				)
				(justify left bottom)
				(hide yes)
			)
		)
		(property "Value" "GND"
			(at 137.16 264.16 0)
			(effects
				(font
					(size 1.27 1.27)
					(thickness 0.15)
				)
			)
		)
		(property "Footprint" ""
			(at 128.27 267.97 0)
			(effects
				(font
					(size 1.27 1.27)
					(thickness 0.15)
				)
				(justify left bottom)
				(hide yes)
			)
		)
		(property "Datasheet" ""
			(at 128.27 273.05 0)
			(effects
				(font
					(size 1.27 1.27)
					(thickness 0.15)
				)
				(justify left bottom)
				(hide yes)
			)
		)
		(property "Description" ""
			(at 137.16 260.35 0)
			(effects
				(font
					(size 1.27 1.27)
				)
				(hide yes)
			)
		)
		(property "Author" "Antmicro"
			(at 128.27 267.97 0)
			(effects
				(font
					(size 1.27 1.27)
					(thickness 0.15)
				)
				(justify left bottom)
				(hide yes)
			)
		)
		(property "License" "Apache-2.0"
			(at 128.27 270.51 0)
			(effects
				(font
					(size 1.27 1.27)
					(thickness 0.15)
				)
				(justify left bottom)
				(hide yes)
			)
		)
		(pin "1"
		)
		(instances
			(project "com-express-7-baseboard"
				(path ""
					(reference "#PWR04")
					(unit 1)
				)
			)
		)
	)
	(symbol
		(lib_id "antmicroResistors0402:R_10k_0402")
		(at 241.3 226.06 270)
		(mirror x)
		(unit 1)
		(exclude_from_sim no)
		(in_bom yes)
		(on_board yes)
		(dnp no)
		(property "Reference" "R25"
			(at 240.03 222.25 90)
			(effects
				(font
					(size 1.27 1.27)
					(thickness 0.15)
				)
				(justify right)
			)
		)
		(property "Value" "R_10k_0402"
			(at 228.6 205.74 0)
			(effects
				(font
					(size 1.27 1.27)
					(thickness 0.15)
				)
				(justify left bottom)
				(hide yes)
			)
		)
		(property "Footprint" "antmicro-footprints:R_0402_1005Metric"
			(at 226.06 205.74 0)
			(effects
				(font
					(size 1.27 1.27)
					(thickness 0.15)
				)
				(justify left bottom)
				(hide yes)
			)
		)
		(property "Datasheet" "https://www.bourns.com/docs/product-datasheets/cr.pdf"
			(at 223.52 205.74 0)
			(effects
				(font
					(size 1.27 1.27)
					(thickness 0.15)
				)
				(justify left bottom)
				(hide yes)
			)
		)
		(property "Description" ""
			(at 241.3 226.06 0)
			(effects
				(font
					(size 1.27 1.27)
				)
				(hide yes)
			)
		)
		(property "MPN" "CR0402-FX-1002GLF"
			(at 220.98 205.74 0)
			(effects
				(font
					(size 1.27 1.27)
					(thickness 0.15)
				)
				(justify left bottom)
				(hide yes)
			)
		)
		(property "Manufacturer" "Bourns"
			(at 218.44 205.74 0)
			(effects
				(font
					(size 1.27 1.27)
					(thickness 0.15)
				)
				(justify left bottom)
				(hide yes)
			)
		)
		(property "License" "Apache-2.0"
			(at 215.9 205.74 0)
			(effects
				(font
					(size 1.27 1.27)
					(thickness 0.15)
				)
				(justify left bottom)
				(hide yes)
			)
		)
		(property "Author" "Antmicro"
			(at 213.36 205.74 0)
			(effects
				(font
					(size 1.27 1.27)
					(thickness 0.15)
				)
				(justify left bottom)
				(hide yes)
			)
		)
		(property "Val" "10k"
			(at 240.03 224.79 90)
			(effects
				(font
					(size 1.27 1.27)
					(thickness 0.15)
				)
				(justify right)
			)
		)
		(property "Tolerance" "1%"
			(at 231.14 205.74 0)
			(effects
				(font
					(size 1.27 1.27)
				)
				(justify left bottom)
				(hide yes)
			)
		)
		(property "Public" "False"
			(at 210.82 205.74 0)
			(effects
				(font
					(size 1.27 1.27)
				)
				(justify left bottom)
				(hide yes)
			)
		)
		(pin "1"
		)
		(pin "2"
		)
		(instances
			(project "com-express-7-baseboard"
				(path ""
					(reference "R25")
					(unit 1)
				)
			)
		)
	)
	(symbol
		(lib_id "antmicroCapacitors0402:C_100n_0402")
		(at 163.83 97.79 90)
		(mirror x)
		(unit 1)
		(exclude_from_sim no)
		(in_bom yes)
		(on_board yes)
		(dnp no)
		(property "Reference" "C5"
			(at 170.18 99.06 90)
			(effects
				(font
					(size 1.27 1.27)
					(thickness 0.15)
				)
				(justify left)
			)
		)
		(property "Value" "C_100n_0402"
			(at 173.99 118.11 0)
			(effects
				(font
					(size 1.27 1.27)
					(thickness 0.15)
				)
				(justify left bottom)
				(hide yes)
			)
		)
		(property "Footprint" "antmicro-footprints:C_0402_1005Metric"
			(at 176.53 118.11 0)
			(effects
				(font
					(size 1.27 1.27)
					(thickness 0.15)
				)
				(justify left bottom)
				(hide yes)
			)
		)
		(property "Datasheet" "https://www.murata.com/products/productdetail?partno=GRM155R61H104KE14%23"
			(at 179.07 118.11 0)
			(effects
				(font
					(size 1.27 1.27)
					(thickness 0.15)
				)
				(justify left bottom)
				(hide yes)
			)
		)
		(property "Description" ""
			(at 163.83 97.79 0)
			(effects
				(font
					(size 1.27 1.27)
				)
				(hide yes)
			)
		)
		(property "MPN" "GRM155R61H104KE14D"
			(at 181.61 118.11 0)
			(effects
				(font
					(size 1.27 1.27)
					(thickness 0.15)
				)
				(justify left bottom)
				(hide yes)
			)
		)
		(property "Manufacturer" "Murata"
			(at 184.15 118.11 0)
			(effects
				(font
					(size 1.27 1.27)
					(thickness 0.15)
				)
				(justify left bottom)
				(hide yes)
			)
		)
		(property "License" "Apache-2.0"
			(at 186.69 118.11 0)
			(effects
				(font
					(size 1.27 1.27)
					(thickness 0.15)
				)
				(justify left bottom)
				(hide yes)
			)
		)
		(property "Author" "Antmicro"
			(at 189.23 118.11 0)
			(effects
				(font
					(size 1.27 1.27)
					(thickness 0.15)
				)
				(justify left bottom)
				(hide yes)
			)
		)
		(property "Val" "100n"
			(at 170.18 101.6 90)
			(effects
				(font
					(size 1.27 1.27)
					(thickness 0.15)
				)
				(justify left)
			)
		)
		(property "Voltage" "50V"
			(at 191.77 118.11 0)
			(effects
				(font
					(size 1.27 1.27)
				)
				(justify left bottom)
				(hide yes)
			)
		)
		(property "Dielectric" "X5R"
			(at 194.31 118.11 0)
			(effects
				(font
					(size 1.27 1.27)
				)
				(justify left bottom)
				(hide yes)
			)
		)
		(property "Public" "False"
			(at 196.85 118.11 0)
			(effects
				(font
					(size 1.27 1.27)
				)
				(justify left bottom)
				(hide yes)
			)
		)
		(pin "1"
		)
		(pin "2"
		)
		(instances
			(project "com-express-7-baseboard"
				(path ""
					(reference "C5")
					(unit 1)
				)
			)
		)
	)
	(symbol
		(lib_id "antmicroResistors0402:R_0R_0402")
		(at 238.76 243.84 0)
		(mirror y)
		(unit 1)
		(exclude_from_sim no)
		(in_bom yes)
		(on_board yes)
		(dnp no)
		(property "Reference" "R23"
			(at 232.41 242.57 0)
			(effects
				(font
					(size 1.27 1.27)
					(thickness 0.15)
				)
			)
		)
		(property "Value" "R_0R_0402"
			(at 218.44 256.54 0)
			(effects
				(font
					(size 1.27 1.27)
					(thickness 0.15)
				)
				(justify left bottom)
				(hide yes)
			)
		)
		(property "Footprint" "antmicro-footprints:R_0402_1005Metric"
			(at 218.44 259.08 0)
			(effects
				(font
					(size 1.27 1.27)
					(thickness 0.15)
				)
				(justify left bottom)
				(hide yes)
			)
		)
		(property "Datasheet" "https://industrial.panasonic.com/cdbs/www-data/pdf/RDA0000/AOA0000C301.pdf"
			(at 218.44 261.62 0)
			(effects
				(font
					(size 1.27 1.27)
					(thickness 0.15)
				)
				(justify left bottom)
				(hide yes)
			)
		)
		(property "Description" ""
			(at 238.76 243.84 0)
			(effects
				(font
					(size 1.27 1.27)
				)
				(hide yes)
			)
		)
		(property "MPN" "ERJ2GE0R00X"
			(at 218.44 264.16 0)
			(effects
				(font
					(size 1.27 1.27)
					(thickness 0.15)
				)
				(justify left bottom)
				(hide yes)
			)
		)
		(property "Manufacturer" "Panasonic"
			(at 218.44 266.7 0)
			(effects
				(font
					(size 1.27 1.27)
					(thickness 0.15)
				)
				(justify left bottom)
				(hide yes)
			)
		)
		(property "License" "Apache-2.0"
			(at 218.44 269.24 0)
			(effects
				(font
					(size 1.27 1.27)
					(thickness 0.15)
				)
				(justify left bottom)
				(hide yes)
			)
		)
		(property "Author" "Antmicro"
			(at 218.44 271.78 0)
			(effects
				(font
					(size 1.27 1.27)
					(thickness 0.15)
				)
				(justify left bottom)
				(hide yes)
			)
		)
		(property "Val" "0R"
			(at 240.03 242.57 0)
			(effects
				(font
					(size 1.27 1.27)
					(thickness 0.15)
				)
			)
		)
		(property "Tolerance" "~"
			(at 218.44 254 0)
			(effects
				(font
					(size 1.27 1.27)
				)
				(justify left bottom)
				(hide yes)
			)
		)
		(property "Current" "1A"
			(at 218.44 274.32 0)
			(effects
				(font
					(size 1.27 1.27)
					(thickness 0.15)
				)
				(justify left bottom)
				(hide yes)
			)
		)
		(property "Public" "False"
			(at 218.44 274.32 0)
			(effects
				(font
					(size 1.27 1.27)
				)
				(justify left bottom)
				(hide yes)
			)
		)
		(pin "1"
		)
		(pin "2"
		)
		(instances
			(project "com-express-7-baseboard"
				(path ""
					(reference "R23")
					(unit 1)
				)
			)
		)
	)
	(symbol
		(lib_id "antmicropower:GND")
		(at 137.16 190.5 0)
		(mirror y)
		(unit 1)
		(exclude_from_sim no)
		(in_bom yes)
		(on_board yes)
		(dnp no)
		(property "Reference" "#PWR03"
			(at 128.27 193.04 0)
			(effects
				(font
					(size 1.27 1.27)
					(thickness 0.15)
				)
				(justify left bottom)
				(hide yes)
			)
		)
		(property "Value" "GND"
			(at 137.16 194.31 0)
			(effects
				(font
					(size 1.27 1.27)
					(thickness 0.15)
				)
			)
		)
		(property "Footprint" ""
			(at 128.27 198.12 0)
			(effects
				(font
					(size 1.27 1.27)
					(thickness 0.15)
				)
				(justify left bottom)
				(hide yes)
			)
		)
		(property "Datasheet" ""
			(at 128.27 203.2 0)
			(effects
				(font
					(size 1.27 1.27)
					(thickness 0.15)
				)
				(justify left bottom)
				(hide yes)
			)
		)
		(property "Description" ""
			(at 137.16 190.5 0)
			(effects
				(font
					(size 1.27 1.27)
				)
				(hide yes)
			)
		)
		(property "Author" "Antmicro"
			(at 128.27 198.12 0)
			(effects
				(font
					(size 1.27 1.27)
					(thickness 0.15)
				)
				(justify left bottom)
				(hide yes)
			)
		)
		(property "License" "Apache-2.0"
			(at 128.27 200.66 0)
			(effects
				(font
					(size 1.27 1.27)
					(thickness 0.15)
				)
				(justify left bottom)
				(hide yes)
			)
		)
		(pin "1"
		)
		(instances
			(project "com-express-7-baseboard"
				(path ""
					(reference "#PWR03")
					(unit 1)
				)
			)
		)
	)
	(symbol
		(lib_id "antmicropower:GND")
		(at 232.41 106.68 0)
		(mirror y)
		(unit 1)
		(exclude_from_sim no)
		(in_bom yes)
		(on_board yes)
		(dnp no)
		(property "Reference" "#PWR020"
			(at 223.52 109.22 0)
			(effects
				(font
					(size 1.27 1.27)
					(thickness 0.15)
				)
				(justify left bottom)
				(hide yes)
			)
		)
		(property "Value" "GND"
			(at 232.41 110.49 0)
			(effects
				(font
					(size 1.27 1.27)
					(thickness 0.15)
				)
			)
		)
		(property "Footprint" ""
			(at 223.52 114.3 0)
			(effects
				(font
					(size 1.27 1.27)
					(thickness 0.15)
				)
				(justify left bottom)
				(hide yes)
			)
		)
		(property "Datasheet" ""
			(at 223.52 119.38 0)
			(effects
				(font
					(size 1.27 1.27)
					(thickness 0.15)
				)
				(justify left bottom)
				(hide yes)
			)
		)
		(property "Description" ""
			(at 232.41 106.68 0)
			(effects
				(font
					(size 1.27 1.27)
				)
				(hide yes)
			)
		)
		(property "Author" "Antmicro"
			(at 223.52 114.3 0)
			(effects
				(font
					(size 1.27 1.27)
					(thickness 0.15)
				)
				(justify left bottom)
				(hide yes)
			)
		)
		(property "License" "Apache-2.0"
			(at 223.52 116.84 0)
			(effects
				(font
					(size 1.27 1.27)
					(thickness 0.15)
				)
				(justify left bottom)
				(hide yes)
			)
		)
		(pin "1"
		)
		(instances
			(project "com-express-7-baseboard"
				(path ""
					(reference "#PWR020")
					(unit 1)
				)
			)
		)
	)
	(symbol
		(lib_id "antmicroResistors0402:R_75R_0402")
		(at 237.49 81.28 0)
		(unit 1)
		(exclude_from_sim no)
		(in_bom yes)
		(on_board yes)
		(dnp no)
		(property "Reference" "R16"
			(at 236.22 80.01 0)
			(effects
				(font
					(size 1.27 1.27)
					(thickness 0.15)
				)
			)
		)
		(property "Value" "R_75R_0402"
			(at 257.81 93.98 0)
			(effects
				(font
					(size 1.27 1.27)
					(thickness 0.15)
				)
				(justify left bottom)
				(hide yes)
			)
		)
		(property "Footprint" "antmicro-footprints:R_0402_1005Metric"
			(at 257.81 96.52 0)
			(effects
				(font
					(size 1.27 1.27)
					(thickness 0.15)
				)
				(justify left bottom)
				(hide yes)
			)
		)
		(property "Datasheet" "https://www.bourns.com/docs/product-datasheets/cr.pdf"
			(at 257.81 99.06 0)
			(effects
				(font
					(size 1.27 1.27)
					(thickness 0.15)
				)
				(justify left bottom)
				(hide yes)
			)
		)
		(property "Description" ""
			(at 237.49 81.28 0)
			(effects
				(font
					(size 1.27 1.27)
				)
				(hide yes)
			)
		)
		(property "MPN" "CR0402-FX-75R0GLF"
			(at 257.81 101.6 0)
			(effects
				(font
					(size 1.27 1.27)
					(thickness 0.15)
				)
				(justify left bottom)
				(hide yes)
			)
		)
		(property "Manufacturer" "Bourns"
			(at 257.81 104.14 0)
			(effects
				(font
					(size 1.27 1.27)
					(thickness 0.15)
				)
				(justify left bottom)
				(hide yes)
			)
		)
		(property "License" "Apache-2.0"
			(at 257.81 106.68 0)
			(effects
				(font
					(size 1.27 1.27)
					(thickness 0.15)
				)
				(justify left bottom)
				(hide yes)
			)
		)
		(property "Author" "Antmicro"
			(at 257.81 109.22 0)
			(effects
				(font
					(size 1.27 1.27)
					(thickness 0.15)
				)
				(justify left bottom)
				(hide yes)
			)
		)
		(property "Val" "75R"
			(at 243.84 80.01 0)
			(effects
				(font
					(size 1.27 1.27)
					(thickness 0.15)
				)
			)
		)
		(property "Tolerance" "1%"
			(at 257.81 91.44 0)
			(effects
				(font
					(size 1.27 1.27)
				)
				(justify left bottom)
				(hide yes)
			)
		)
		(property "Public" "False"
			(at 257.81 111.76 0)
			(effects
				(font
					(size 1.27 1.27)
				)
				(justify left bottom)
				(hide yes)
			)
		)
		(pin "2"
		)
		(pin "1"
		)
		(instances
			(project "com-express-7-baseboard"
				(path ""
					(reference "R16")
					(unit 1)
				)
			)
		)
	)
	(symbol
		(lib_id "antmicropower:GND")
		(at 195.58 233.68 0)
		(mirror y)
		(unit 1)
		(exclude_from_sim no)
		(in_bom yes)
		(on_board yes)
		(dnp no)
		(property "Reference" "#PWR015"
			(at 186.69 236.22 0)
			(effects
				(font
					(size 1.27 1.27)
					(thickness 0.15)
				)
				(justify left bottom)
				(hide yes)
			)
		)
		(property "Value" "GND"
			(at 195.58 237.49 0)
			(effects
				(font
					(size 1.27 1.27)
					(thickness 0.15)
				)
			)
		)
		(property "Footprint" ""
			(at 186.69 241.3 0)
			(effects
				(font
					(size 1.27 1.27)
					(thickness 0.15)
				)
				(justify left bottom)
				(hide yes)
			)
		)
		(property "Datasheet" ""
			(at 186.69 246.38 0)
			(effects
				(font
					(size 1.27 1.27)
					(thickness 0.15)
				)
				(justify left bottom)
				(hide yes)
			)
		)
		(property "Description" ""
			(at 195.58 233.68 0)
			(effects
				(font
					(size 1.27 1.27)
				)
				(hide yes)
			)
		)
		(property "Author" "Antmicro"
			(at 186.69 241.3 0)
			(effects
				(font
					(size 1.27 1.27)
					(thickness 0.15)
				)
				(justify left bottom)
				(hide yes)
			)
		)
		(property "License" "Apache-2.0"
			(at 186.69 243.84 0)
			(effects
				(font
					(size 1.27 1.27)
					(thickness 0.15)
				)
				(justify left bottom)
				(hide yes)
			)
		)
		(pin "1"
		)
		(instances
			(project "com-express-7-baseboard"
				(path ""
					(reference "#PWR015")
					(unit 1)
				)
			)
		)
	)
	(symbol
		(lib_id "antmicroModularConnectorsJacks:Amphenol_RJE361882415")
		(at 162.56 63.5 0)
		(mirror y)
		(unit 1)
		(exclude_from_sim no)
		(in_bom yes)
		(on_board yes)
		(dnp no)
		(property "Reference" "J1"
			(at 149.86 55.88 0)
			(effects
				(font
					(size 1.27 1.27)
				)
			)
		)
		(property "Value" "Amphenol_RJE361882415"
			(at 149.86 58.42 0)
			(effects
				(font
					(size 1.27 1.27)
				)
				(hide yes)
			)
		)
		(property "Footprint" "antmicro-footprints:RJ45_RJE361882415"
			(at 124.46 119.38 0)
			(effects
				(font
					(size 1.27 1.27)
				)
				(hide yes)
			)
		)
		(property "Datasheet" "https://cdn.amphenol-cs.com/media/wysiwyg/files/drawing/p-rje36-188-2xx5.pdf"
			(at 124.46 119.38 0)
			(effects
				(font
					(size 1.27 1.27)
				)
				(hide yes)
			)
		)
		(property "Description" ""
			(at 162.56 63.5 0)
			(effects
				(font
					(size 1.27 1.27)
				)
				(hide yes)
			)
		)
		(property "MPN" "RJE361882415"
			(at 149.86 58.42 0)
			(effects
				(font
					(size 1.27 1.27)
				)
			)
		)
		(property "Manufacturer" "Amphenol"
			(at 162.56 63.5 0)
			(effects
				(font
					(size 1.27 1.27)
				)
				(hide yes)
			)
		)
		(property "Author" "Antmicro"
			(at 123.19 83.82 0)
			(effects
				(font
					(size 1.27 1.27)
					(thickness 0.15)
				)
				(justify left bottom)
				(hide yes)
			)
		)
		(property "License" "Apache-2.0"
			(at 123.19 86.36 0)
			(effects
				(font
					(size 1.27 1.27)
					(thickness 0.15)
				)
				(justify left bottom)
				(hide yes)
			)
		)
		(pin "U2"
		)
		(pin "1"
		)
		(pin "U10"
		)
		(pin "U5"
		)
		(pin "U4"
		)
		(pin "U17"
		)
		(pin "U7"
		)
		(pin "U14"
		)
		(pin "U6"
		)
		(pin "U12"
		)
		(pin "U13"
		)
		(pin "D4"
		)
		(pin "U18"
		)
		(pin "U1"
		)
		(pin "8"
		)
		(pin "MP"
		)
		(pin "U15"
		)
		(pin "6"
		)
		(pin "U16"
		)
		(pin "U9"
		)
		(pin "D2"
		)
		(pin "3"
		)
		(pin "2"
		)
		(pin "D3"
		)
		(pin "7"
		)
		(pin "4"
		)
		(pin "U11"
		)
		(pin "5"
		)
		(pin "D1"
		)
		(pin "U3"
		)
		(pin "U8"
		)
		(instances
			(project "com-express-7-baseboard"
				(path ""
					(reference "J1")
					(unit 1)
				)
			)
		)
	)
	(symbol
		(lib_id "antmicroCommonModeChokes:Choke_SRF2012A-801Y")
		(at 220.98 53.34 0)
		(mirror y)
		(unit 1)
		(exclude_from_sim no)
		(in_bom yes)
		(on_board yes)
		(dnp no)
		(fields_autoplaced yes)
		(property "Reference" "T1"
			(at 216.281 48.26 0)
			(effects
				(font
					(size 1.27 1.27)
					(thickness 0.15)
				)
			)
		)
		(property "Value" "Choke_SRF2012A-801Y"
			(at 205.74 63.5 0)
			(effects
				(font
					(size 1.27 1.27)
					(thickness 0.15)
				)
				(justify left bottom)
				(hide yes)
			)
		)
		(property "Footprint" "antmicro-footprints:Choke_0805_2012Metric"
			(at 194.31 66.04 0)
			(effects
				(font
					(size 1.27 1.27)
					(thickness 0.15)
				)
				(justify left bottom)
				(hide yes)
			)
		)
		(property "Datasheet" "https://www.bourns.com/docs/product-datasheets/srf2012a-801y.pdf"
			(at 205.74 68.58 0)
			(effects
				(font
					(size 1.27 1.27)
					(thickness 0.15)
				)
				(justify left bottom)
				(hide yes)
			)
		)
		(property "Description" ""
			(at 220.98 53.34 0)
			(effects
				(font
					(size 1.27 1.27)
				)
				(hide yes)
			)
		)
		(property "Manufacturer" "Bourns"
			(at 205.74 71.12 0)
			(effects
				(font
					(size 1.27 1.27)
					(thickness 0.15)
				)
				(justify left bottom)
				(hide yes)
			)
		)
		(property "MPN" "SRF2012A-801Y"
			(at 216.281 50.8 0)
			(effects
				(font
					(size 1.27 1.27)
					(thickness 0.15)
				)
			)
		)
		(property "IMax" "0.3 A"
			(at 205.74 73.66 0)
			(effects
				(font
					(size 1.27 1.27)
					(thickness 0.15)
				)
				(justify left bottom)
				(hide yes)
			)
		)
		(property "Author" "Antmicro"
			(at 205.74 76.2 0)
			(effects
				(font
					(size 1.27 1.27)
					(thickness 0.15)
				)
				(justify left bottom)
				(hide yes)
			)
		)
		(property "License" "Apache-2.0"
			(at 205.74 78.74 0)
			(effects
				(font
					(size 1.27 1.27)
					(thickness 0.15)
				)
				(justify left bottom)
				(hide yes)
			)
		)
		(property "Public" "False"
			(at 194.31 86.36 0)
			(effects
				(font
					(size 1.27 1.27)
				)
				(justify left bottom)
				(hide yes)
			)
		)
		(pin "3"
		)
		(pin "4"
		)
		(pin "1"
		)
		(pin "2"
		)
		(instances
			(project "com-express-7-baseboard"
				(path ""
					(reference "T1")
					(unit 1)
				)
			)
		)
	)
	(symbol
		(lib_id "antmicropower:GND")
		(at 149.86 233.68 0)
		(mirror y)
		(unit 1)
		(exclude_from_sim no)
		(in_bom yes)
		(on_board yes)
		(dnp no)
		(property "Reference" "#PWR06"
			(at 140.97 236.22 0)
			(effects
				(font
					(size 1.27 1.27)
					(thickness 0.15)
				)
				(justify left bottom)
				(hide yes)
			)
		)
		(property "Value" "GND"
			(at 149.86 237.49 0)
			(effects
				(font
					(size 1.27 1.27)
					(thickness 0.15)
				)
			)
		)
		(property "Footprint" ""
			(at 140.97 241.3 0)
			(effects
				(font
					(size 1.27 1.27)
					(thickness 0.15)
				)
				(justify left bottom)
				(hide yes)
			)
		)
		(property "Datasheet" ""
			(at 140.97 246.38 0)
			(effects
				(font
					(size 1.27 1.27)
					(thickness 0.15)
				)
				(justify left bottom)
				(hide yes)
			)
		)
		(property "Description" ""
			(at 149.86 233.68 0)
			(effects
				(font
					(size 1.27 1.27)
				)
				(hide yes)
			)
		)
		(property "Author" "Antmicro"
			(at 140.97 241.3 0)
			(effects
				(font
					(size 1.27 1.27)
					(thickness 0.15)
				)
				(justify left bottom)
				(hide yes)
			)
		)
		(property "License" "Apache-2.0"
			(at 140.97 243.84 0)
			(effects
				(font
					(size 1.27 1.27)
					(thickness 0.15)
				)
				(justify left bottom)
				(hide yes)
			)
		)
		(pin "1"
		)
		(instances
			(project "com-express-7-baseboard"
				(path ""
					(reference "#PWR06")
					(unit 1)
				)
			)
		)
	)
	(symbol
		(lib_id "antmicropower:GND")
		(at 149.86 163.83 0)
		(mirror y)
		(unit 1)
		(exclude_from_sim no)
		(in_bom yes)
		(on_board yes)
		(dnp no)
		(property "Reference" "#PWR05"
			(at 140.97 166.37 0)
			(effects
				(font
					(size 1.27 1.27)
					(thickness 0.15)
				)
				(justify left bottom)
				(hide yes)
			)
		)
		(property "Value" "GND"
			(at 149.86 167.64 0)
			(effects
				(font
					(size 1.27 1.27)
					(thickness 0.15)
				)
			)
		)
		(property "Footprint" ""
			(at 140.97 171.45 0)
			(effects
				(font
					(size 1.27 1.27)
					(thickness 0.15)
				)
				(justify left bottom)
				(hide yes)
			)
		)
		(property "Datasheet" ""
			(at 140.97 176.53 0)
			(effects
				(font
					(size 1.27 1.27)
					(thickness 0.15)
				)
				(justify left bottom)
				(hide yes)
			)
		)
		(property "Description" ""
			(at 149.86 163.83 0)
			(effects
				(font
					(size 1.27 1.27)
				)
				(hide yes)
			)
		)
		(property "Author" "Antmicro"
			(at 140.97 171.45 0)
			(effects
				(font
					(size 1.27 1.27)
					(thickness 0.15)
				)
				(justify left bottom)
				(hide yes)
			)
		)
		(property "License" "Apache-2.0"
			(at 140.97 173.99 0)
			(effects
				(font
					(size 1.27 1.27)
					(thickness 0.15)
				)
				(justify left bottom)
				(hide yes)
			)
		)
		(pin "1"
		)
		(instances
			(project "com-express-7-baseboard"
				(path ""
					(reference "#PWR05")
					(unit 1)
				)
			)
		)
	)
	(symbol
		(lib_id "antmicropower:+5V")
		(at 280.67 210.82 0)
		(mirror y)
		(unit 1)
		(exclude_from_sim no)
		(in_bom yes)
		(on_board yes)
		(dnp no)
		(property "Reference" "#PWR033"
			(at 265.43 213.36 0)
			(effects
				(font
					(size 1.27 1.27)
					(thickness 0.15)
				)
				(justify left bottom)
				(hide yes)
			)
		)
		(property "Value" "+5V"
			(at 280.67 207.01 0)
			(effects
				(font
					(size 1.27 1.27)
					(thickness 0.15)
				)
			)
		)
		(property "Footprint" ""
			(at 265.43 218.44 0)
			(effects
				(font
					(size 1.27 1.27)
					(thickness 0.15)
				)
				(justify left bottom)
				(hide yes)
			)
		)
		(property "Datasheet" ""
			(at 265.43 220.98 0)
			(effects
				(font
					(size 1.27 1.27)
					(thickness 0.15)
				)
				(justify left bottom)
				(hide yes)
			)
		)
		(property "Description" ""
			(at 280.67 210.82 0)
			(effects
				(font
					(size 1.27 1.27)
				)
				(hide yes)
			)
		)
		(property "Author" "Antmicro"
			(at 265.43 218.44 0)
			(effects
				(font
					(size 1.27 1.27)
					(thickness 0.15)
				)
				(justify left bottom)
				(hide yes)
			)
		)
		(property "License" "Apache-2.0"
			(at 265.43 220.98 0)
			(effects
				(font
					(size 1.27 1.27)
					(thickness 0.15)
				)
				(justify left bottom)
				(hide yes)
			)
		)
		(pin "1"
		)
		(instances
			(project "com-express-7-baseboard"
				(path ""
					(reference "#PWR033")
					(unit 1)
				)
			)
		)
	)
	(symbol
		(lib_id "antmicropower:GND")
		(at 160.02 163.83 0)
		(unit 1)
		(exclude_from_sim no)
		(in_bom yes)
		(on_board yes)
		(dnp no)
		(property "Reference" "#PWR07"
			(at 168.91 166.37 0)
			(effects
				(font
					(size 1.27 1.27)
					(thickness 0.15)
				)
				(justify left bottom)
				(hide yes)
			)
		)
		(property "Value" "GND"
			(at 160.02 167.64 0)
			(effects
				(font
					(size 1.27 1.27)
					(thickness 0.15)
				)
			)
		)
		(property "Footprint" ""
			(at 168.91 171.45 0)
			(effects
				(font
					(size 1.27 1.27)
					(thickness 0.15)
				)
				(justify left bottom)
				(hide yes)
			)
		)
		(property "Datasheet" ""
			(at 168.91 176.53 0)
			(effects
				(font
					(size 1.27 1.27)
					(thickness 0.15)
				)
				(justify left bottom)
				(hide yes)
			)
		)
		(property "Description" ""
			(at 160.02 163.83 0)
			(effects
				(font
					(size 1.27 1.27)
				)
				(hide yes)
			)
		)
		(property "Author" "Antmicro"
			(at 168.91 171.45 0)
			(effects
				(font
					(size 1.27 1.27)
					(thickness 0.15)
				)
				(justify left bottom)
				(hide yes)
			)
		)
		(property "License" "Apache-2.0"
			(at 168.91 173.99 0)
			(effects
				(font
					(size 1.27 1.27)
					(thickness 0.15)
				)
				(justify left bottom)
				(hide yes)
			)
		)
		(pin "1"
		)
		(instances
			(project "com-express-7-baseboard"
				(path ""
					(reference "#PWR07")
					(unit 1)
				)
			)
		)
	)
	(symbol
		(lib_id "antmicroResistors0402:R_75R_0402")
		(at 237.49 55.88 0)
		(unit 1)
		(exclude_from_sim no)
		(in_bom yes)
		(on_board yes)
		(dnp no)
		(property "Reference" "R14"
			(at 236.22 54.61 0)
			(effects
				(font
					(size 1.27 1.27)
					(thickness 0.15)
				)
			)
		)
		(property "Value" "R_75R_0402"
			(at 257.81 68.58 0)
			(effects
				(font
					(size 1.27 1.27)
					(thickness 0.15)
				)
				(justify left bottom)
				(hide yes)
			)
		)
		(property "Footprint" "antmicro-footprints:R_0402_1005Metric"
			(at 257.81 71.12 0)
			(effects
				(font
					(size 1.27 1.27)
					(thickness 0.15)
				)
				(justify left bottom)
				(hide yes)
			)
		)
		(property "Datasheet" "https://www.bourns.com/docs/product-datasheets/cr.pdf"
			(at 257.81 73.66 0)
			(effects
				(font
					(size 1.27 1.27)
					(thickness 0.15)
				)
				(justify left bottom)
				(hide yes)
			)
		)
		(property "Description" ""
			(at 237.49 55.88 0)
			(effects
				(font
					(size 1.27 1.27)
				)
				(hide yes)
			)
		)
		(property "MPN" "CR0402-FX-75R0GLF"
			(at 257.81 76.2 0)
			(effects
				(font
					(size 1.27 1.27)
					(thickness 0.15)
				)
				(justify left bottom)
				(hide yes)
			)
		)
		(property "Manufacturer" "Bourns"
			(at 257.81 78.74 0)
			(effects
				(font
					(size 1.27 1.27)
					(thickness 0.15)
				)
				(justify left bottom)
				(hide yes)
			)
		)
		(property "License" "Apache-2.0"
			(at 257.81 81.28 0)
			(effects
				(font
					(size 1.27 1.27)
					(thickness 0.15)
				)
				(justify left bottom)
				(hide yes)
			)
		)
		(property "Author" "Antmicro"
			(at 257.81 83.82 0)
			(effects
				(font
					(size 1.27 1.27)
					(thickness 0.15)
				)
				(justify left bottom)
				(hide yes)
			)
		)
		(property "Val" "75R"
			(at 243.84 54.61 0)
			(effects
				(font
					(size 1.27 1.27)
					(thickness 0.15)
				)
			)
		)
		(property "Tolerance" "1%"
			(at 257.81 66.04 0)
			(effects
				(font
					(size 1.27 1.27)
				)
				(justify left bottom)
				(hide yes)
			)
		)
		(property "Public" "False"
			(at 257.81 86.36 0)
			(effects
				(font
					(size 1.27 1.27)
				)
				(justify left bottom)
				(hide yes)
			)
		)
		(pin "2"
		)
		(pin "1"
		)
		(instances
			(project "com-express-7-baseboard"
				(path ""
					(reference "R14")
					(unit 1)
				)
			)
		)
	)
	(symbol
		(lib_id "antmicroCapacitors0402:C_100n_0402")
		(at 280.67 100.33 270)
		(unit 1)
		(exclude_from_sim no)
		(in_bom yes)
		(on_board yes)
		(dnp no)
		(property "Reference" "C18"
			(at 281.305 100.965 90)
			(effects
				(font
					(size 1.27 1.27)
					(thickness 0.15)
				)
				(justify left)
			)
		)
		(property "Value" "C_100n_0402"
			(at 270.51 120.65 0)
			(effects
				(font
					(size 1.27 1.27)
					(thickness 0.15)
				)
				(justify left bottom)
				(hide yes)
			)
		)
		(property "Footprint" "antmicro-footprints:C_0402_1005Metric"
			(at 267.97 120.65 0)
			(effects
				(font
					(size 1.27 1.27)
					(thickness 0.15)
				)
				(justify left bottom)
				(hide yes)
			)
		)
		(property "Datasheet" "https://www.murata.com/products/productdetail?partno=GRM155R61H104KE14%23"
			(at 265.43 120.65 0)
			(effects
				(font
					(size 1.27 1.27)
					(thickness 0.15)
				)
				(justify left bottom)
				(hide yes)
			)
		)
		(property "Description" ""
			(at 280.67 100.33 0)
			(effects
				(font
					(size 1.27 1.27)
				)
				(hide yes)
			)
		)
		(property "MPN" "GRM155R61H104KE14D"
			(at 262.89 120.65 0)
			(effects
				(font
					(size 1.27 1.27)
					(thickness 0.15)
				)
				(justify left bottom)
				(hide yes)
			)
		)
		(property "Manufacturer" "Murata"
			(at 260.35 120.65 0)
			(effects
				(font
					(size 1.27 1.27)
					(thickness 0.15)
				)
				(justify left bottom)
				(hide yes)
			)
		)
		(property "License" "Apache-2.0"
			(at 257.81 120.65 0)
			(effects
				(font
					(size 1.27 1.27)
					(thickness 0.15)
				)
				(justify left bottom)
				(hide yes)
			)
		)
		(property "Author" "Antmicro"
			(at 255.27 120.65 0)
			(effects
				(font
					(size 1.27 1.27)
					(thickness 0.15)
				)
				(justify left bottom)
				(hide yes)
			)
		)
		(property "Val" "100n"
			(at 281.305 104.775 90)
			(effects
				(font
					(size 1.27 1.27)
					(thickness 0.15)
				)
				(justify left)
			)
		)
		(property "Voltage" "50V"
			(at 252.73 120.65 0)
			(effects
				(font
					(size 1.27 1.27)
				)
				(justify left bottom)
				(hide yes)
			)
		)
		(property "Dielectric" "X5R"
			(at 250.19 120.65 0)
			(effects
				(font
					(size 1.27 1.27)
				)
				(justify left bottom)
				(hide yes)
			)
		)
		(property "Public" "False"
			(at 247.65 120.65 0)
			(effects
				(font
					(size 1.27 1.27)
				)
				(justify left bottom)
				(hide yes)
			)
		)
		(pin "2"
		)
		(pin "1"
		)
		(instances
			(project "com-express-7-baseboard"
				(path ""
					(reference "C18")
					(unit 1)
				)
			)
		)
	)
	(symbol
		(lib_id "antmicropower:GND")
		(at 195.58 163.83 0)
		(mirror y)
		(unit 1)
		(exclude_from_sim no)
		(in_bom yes)
		(on_board yes)
		(dnp no)
		(property "Reference" "#PWR014"
			(at 186.69 166.37 0)
			(effects
				(font
					(size 1.27 1.27)
					(thickness 0.15)
				)
				(justify left bottom)
				(hide yes)
			)
		)
		(property "Value" "GND"
			(at 195.58 167.64 0)
			(effects
				(font
					(size 1.27 1.27)
					(thickness 0.15)
				)
			)
		)
		(property "Footprint" ""
			(at 186.69 171.45 0)
			(effects
				(font
					(size 1.27 1.27)
					(thickness 0.15)
				)
				(justify left bottom)
				(hide yes)
			)
		)
		(property "Datasheet" ""
			(at 186.69 176.53 0)
			(effects
				(font
					(size 1.27 1.27)
					(thickness 0.15)
				)
				(justify left bottom)
				(hide yes)
			)
		)
		(property "Description" ""
			(at 195.58 163.83 0)
			(effects
				(font
					(size 1.27 1.27)
				)
				(hide yes)
			)
		)
		(property "Author" "Antmicro"
			(at 186.69 171.45 0)
			(effects
				(font
					(size 1.27 1.27)
					(thickness 0.15)
				)
				(justify left bottom)
				(hide yes)
			)
		)
		(property "License" "Apache-2.0"
			(at 186.69 173.99 0)
			(effects
				(font
					(size 1.27 1.27)
					(thickness 0.15)
				)
				(justify left bottom)
				(hide yes)
			)
		)
		(pin "1"
		)
		(instances
			(project "com-express-7-baseboard"
				(path ""
					(reference "#PWR014")
					(unit 1)
				)
			)
		)
	)
	(symbol
		(lib_id "antmicroResistors0402:R_0R_0402")
		(at 254 229.87 0)
		(mirror y)
		(unit 1)
		(exclude_from_sim no)
		(in_bom yes)
		(on_board yes)
		(dnp no)
		(property "Reference" "R29"
			(at 256.54 228.6 0)
			(effects
				(font
					(size 1.27 1.27)
					(thickness 0.15)
				)
			)
		)
		(property "Value" "R_0R_0402"
			(at 233.68 242.57 0)
			(effects
				(font
					(size 1.27 1.27)
					(thickness 0.15)
				)
				(justify left bottom)
				(hide yes)
			)
		)
		(property "Footprint" "antmicro-footprints:R_0402_1005Metric"
			(at 233.68 245.11 0)
			(effects
				(font
					(size 1.27 1.27)
					(thickness 0.15)
				)
				(justify left bottom)
				(hide yes)
			)
		)
		(property "Datasheet" "https://industrial.panasonic.com/cdbs/www-data/pdf/RDA0000/AOA0000C301.pdf"
			(at 233.68 247.65 0)
			(effects
				(font
					(size 1.27 1.27)
					(thickness 0.15)
				)
				(justify left bottom)
				(hide yes)
			)
		)
		(property "Description" ""
			(at 254 229.87 0)
			(effects
				(font
					(size 1.27 1.27)
				)
				(hide yes)
			)
		)
		(property "MPN" "ERJ2GE0R00X"
			(at 233.68 250.19 0)
			(effects
				(font
					(size 1.27 1.27)
					(thickness 0.15)
				)
				(justify left bottom)
				(hide yes)
			)
		)
		(property "Manufacturer" "Panasonic"
			(at 233.68 252.73 0)
			(effects
				(font
					(size 1.27 1.27)
					(thickness 0.15)
				)
				(justify left bottom)
				(hide yes)
			)
		)
		(property "License" "Apache-2.0"
			(at 233.68 255.27 0)
			(effects
				(font
					(size 1.27 1.27)
					(thickness 0.15)
				)
				(justify left bottom)
				(hide yes)
			)
		)
		(property "Author" "Antmicro"
			(at 233.68 257.81 0)
			(effects
				(font
					(size 1.27 1.27)
					(thickness 0.15)
				)
				(justify left bottom)
				(hide yes)
			)
		)
		(property "Val" "0R"
			(at 247.65 228.6 0)
			(effects
				(font
					(size 1.27 1.27)
					(thickness 0.15)
				)
			)
		)
		(property "Tolerance" "~"
			(at 233.68 240.03 0)
			(effects
				(font
					(size 1.27 1.27)
				)
				(justify left bottom)
				(hide yes)
			)
		)
		(property "Current" "1A"
			(at 233.68 260.35 0)
			(effects
				(font
					(size 1.27 1.27)
					(thickness 0.15)
				)
				(justify left bottom)
				(hide yes)
			)
		)
		(property "Public" "False"
			(at 233.68 260.35 0)
			(effects
				(font
					(size 1.27 1.27)
				)
				(justify left bottom)
				(hide yes)
			)
		)
		(pin "1"
		)
		(pin "2"
		)
		(instances
			(project "com-express-7-baseboard"
				(path ""
					(reference "R29")
					(unit 1)
				)
			)
		)
	)
	(symbol
		(lib_id "antmicroResistors0402:R_330R_0402")
		(at 160.02 97.79 90)
		(mirror x)
		(unit 1)
		(exclude_from_sim no)
		(in_bom yes)
		(on_board yes)
		(dnp no)
		(property "Reference" "R11"
			(at 158.75 99.06 90)
			(effects
				(font
					(size 1.27 1.27)
					(thickness 0.15)
				)
				(justify left)
			)
		)
		(property "Value" "R_330R_0402"
			(at 172.72 118.11 0)
			(effects
				(font
					(size 1.27 1.27)
					(thickness 0.15)
				)
				(justify left bottom)
				(hide yes)
			)
		)
		(property "Footprint" "antmicro-footprints:R_0402_1005Metric"
			(at 175.26 118.11 0)
			(effects
				(font
					(size 1.27 1.27)
					(thickness 0.15)
				)
				(justify left bottom)
				(hide yes)
			)
		)
		(property "Datasheet" "https://www.bourns.com/docs/product-datasheets/cr.pdf"
			(at 177.8 118.11 0)
			(effects
				(font
					(size 1.27 1.27)
					(thickness 0.15)
				)
				(justify left bottom)
				(hide yes)
			)
		)
		(property "Description" ""
			(at 160.02 97.79 0)
			(effects
				(font
					(size 1.27 1.27)
				)
				(hide yes)
			)
		)
		(property "MPN" "CR0402-FX-3300GLF"
			(at 180.34 118.11 0)
			(effects
				(font
					(size 1.27 1.27)
					(thickness 0.15)
				)
				(justify left bottom)
				(hide yes)
			)
		)
		(property "Manufacturer" "Bourns"
			(at 182.88 118.11 0)
			(effects
				(font
					(size 1.27 1.27)
					(thickness 0.15)
				)
				(justify left bottom)
				(hide yes)
			)
		)
		(property "License" "Apache-2.0"
			(at 185.42 118.11 0)
			(effects
				(font
					(size 1.27 1.27)
					(thickness 0.15)
				)
				(justify left bottom)
				(hide yes)
			)
		)
		(property "Author" "Antmicro"
			(at 187.96 118.11 0)
			(effects
				(font
					(size 1.27 1.27)
					(thickness 0.15)
				)
				(justify left bottom)
				(hide yes)
			)
		)
		(property "Val" "330R"
			(at 158.75 101.6 90)
			(effects
				(font
					(size 1.27 1.27)
					(thickness 0.15)
				)
				(justify left)
			)
		)
		(property "Tolerance" "1%"
			(at 170.18 118.11 0)
			(effects
				(font
					(size 1.27 1.27)
				)
				(justify left bottom)
				(hide yes)
			)
		)
		(property "Public" "False"
			(at 190.5 118.11 0)
			(effects
				(font
					(size 1.27 1.27)
				)
				(justify left bottom)
				(hide yes)
			)
		)
		(pin "1"
		)
		(pin "2"
		)
		(instances
			(project "com-express-7-baseboard"
				(path ""
					(reference "R11")
					(unit 1)
				)
			)
		)
	)
	(symbol
		(lib_id "antmicroCapacitorspol:C_Pol_100u_10V_KEMET-T520-B")
		(at 160.02 227.33 270)
		(unit 1)
		(exclude_from_sim no)
		(in_bom yes)
		(on_board yes)
		(dnp no)
		(fields_autoplaced yes)
		(property "Reference" "C4"
			(at 162.56 226.7965 90)
			(effects
				(font
					(size 1.27 1.27)
					(thickness 0.15)
				)
				(justify left)
			)
		)
		(property "Value" "C_Pol_100u_10V_KEMET-T520-B"
			(at 157.48 241.3 0)
			(effects
				(font
					(size 1.27 1.27)
					(thickness 0.15)
				)
				(justify left bottom)
				(hide yes)
			)
		)
		(property "Footprint" "antmicro-footprints:C_Pol_EIA-B"
			(at 152.4 241.3 0)
			(effects
				(font
					(size 1.27 1.27)
					(thickness 0.15)
				)
				(justify left bottom)
				(hide yes)
			)
		)
		(property "Datasheet" "https://www.kemet.com/en/us/capacitors/product/T520B107M010ATE070.html"
			(at 149.86 241.3 0)
			(effects
				(font
					(size 1.27 1.27)
					(thickness 0.15)
				)
				(justify left bottom)
				(hide yes)
			)
		)
		(property "Description" ""
			(at 160.02 227.33 0)
			(effects
				(font
					(size 1.27 1.27)
				)
				(hide yes)
			)
		)
		(property "Val" "100u"
			(at 162.56 229.3365 90)
			(effects
				(font
					(size 1.27 1.27)
					(thickness 0.15)
				)
				(justify left)
			)
		)
		(property "MPN" "T520B107M010ATE070"
			(at 147.32 241.3 0)
			(effects
				(font
					(size 1.27 1.27)
					(thickness 0.15)
				)
				(justify left bottom)
				(hide yes)
			)
		)
		(property "Manufacturer" "KEMET"
			(at 144.78 241.3 0)
			(effects
				(font
					(size 1.27 1.27)
					(thickness 0.15)
				)
				(justify left bottom)
				(hide yes)
			)
		)
		(property "License" "Apache-2.0"
			(at 142.24 241.3 0)
			(effects
				(font
					(size 1.27 1.27)
					(thickness 0.15)
				)
				(justify left bottom)
				(hide yes)
			)
		)
		(property "Author" "Antmicro"
			(at 139.7 241.3 0)
			(effects
				(font
					(size 1.27 1.27)
					(thickness 0.15)
				)
				(justify left bottom)
				(hide yes)
			)
		)
		(property "Voltage" "10V"
			(at 162.56 231.8765 90)
			(effects
				(font
					(size 1.27 1.27)
				)
				(justify left)
			)
		)
		(property "Dielectric" "template_dielectric"
			(at 134.62 241.3 0)
			(effects
				(font
					(size 1.27 1.27)
				)
				(justify left bottom)
				(hide yes)
			)
		)
		(property "Public" "False"
			(at 132.08 241.3 0)
			(effects
				(font
					(size 1.27 1.27)
				)
				(justify left bottom)
				(hide yes)
			)
		)
		(pin "1"
		)
		(pin "2"
		)
		(instances
			(project "com-express-7-baseboard"
				(path ""
					(reference "C4")
					(unit 1)
				)
			)
		)
	)
	(symbol
		(lib_id "antmicroResistors0402:R_75R_0402")
		(at 237.49 93.98 0)
		(unit 1)
		(exclude_from_sim no)
		(in_bom yes)
		(on_board yes)
		(dnp no)
		(property "Reference" "R17"
			(at 236.22 92.71 0)
			(effects
				(font
					(size 1.27 1.27)
					(thickness 0.15)
				)
			)
		)
		(property "Value" "R_75R_0402"
			(at 257.81 106.68 0)
			(effects
				(font
					(size 1.27 1.27)
					(thickness 0.15)
				)
				(justify left bottom)
				(hide yes)
			)
		)
		(property "Footprint" "antmicro-footprints:R_0402_1005Metric"
			(at 257.81 109.22 0)
			(effects
				(font
					(size 1.27 1.27)
					(thickness 0.15)
				)
				(justify left bottom)
				(hide yes)
			)
		)
		(property "Datasheet" "https://www.bourns.com/docs/product-datasheets/cr.pdf"
			(at 257.81 111.76 0)
			(effects
				(font
					(size 1.27 1.27)
					(thickness 0.15)
				)
				(justify left bottom)
				(hide yes)
			)
		)
		(property "Description" ""
			(at 237.49 93.98 0)
			(effects
				(font
					(size 1.27 1.27)
				)
				(hide yes)
			)
		)
		(property "MPN" "CR0402-FX-75R0GLF"
			(at 257.81 114.3 0)
			(effects
				(font
					(size 1.27 1.27)
					(thickness 0.15)
				)
				(justify left bottom)
				(hide yes)
			)
		)
		(property "Manufacturer" "Bourns"
			(at 257.81 116.84 0)
			(effects
				(font
					(size 1.27 1.27)
					(thickness 0.15)
				)
				(justify left bottom)
				(hide yes)
			)
		)
		(property "License" "Apache-2.0"
			(at 257.81 119.38 0)
			(effects
				(font
					(size 1.27 1.27)
					(thickness 0.15)
				)
				(justify left bottom)
				(hide yes)
			)
		)
		(property "Author" "Antmicro"
			(at 257.81 121.92 0)
			(effects
				(font
					(size 1.27 1.27)
					(thickness 0.15)
				)
				(justify left bottom)
				(hide yes)
			)
		)
		(property "Val" "75R"
			(at 243.84 92.71 0)
			(effects
				(font
					(size 1.27 1.27)
					(thickness 0.15)
				)
			)
		)
		(property "Tolerance" "1%"
			(at 257.81 104.14 0)
			(effects
				(font
					(size 1.27 1.27)
				)
				(justify left bottom)
				(hide yes)
			)
		)
		(property "Public" "False"
			(at 257.81 124.46 0)
			(effects
				(font
					(size 1.27 1.27)
				)
				(justify left bottom)
				(hide yes)
			)
		)
		(pin "2"
		)
		(pin "1"
		)
		(instances
			(project "com-express-7-baseboard"
				(path ""
					(reference "R17")
					(unit 1)
				)
			)
		)
	)
	(symbol
		(lib_id "antmicroResistors0402:R_0R_0402")
		(at 93.98 83.82 0)
		(unit 1)
		(exclude_from_sim no)
		(in_bom yes)
		(on_board yes)
		(dnp yes)
		(property "Reference" "R3"
			(at 92.71 82.55 0)
			(effects
				(font
					(size 1.27 1.27)
					(thickness 0.15)
				)
			)
		)
		(property "Value" "R_0R_0402"
			(at 114.3 96.52 0)
			(effects
				(font
					(size 1.27 1.27)
					(thickness 0.15)
				)
				(justify left bottom)
				(hide yes)
			)
		)
		(property "Footprint" "antmicro-footprints:R_0402_1005Metric"
			(at 114.3 99.06 0)
			(effects
				(font
					(size 1.27 1.27)
					(thickness 0.15)
				)
				(justify left bottom)
				(hide yes)
			)
		)
		(property "Datasheet" "https://industrial.panasonic.com/cdbs/www-data/pdf/RDA0000/AOA0000C301.pdf"
			(at 114.3 101.6 0)
			(effects
				(font
					(size 1.27 1.27)
					(thickness 0.15)
				)
				(justify left bottom)
				(hide yes)
			)
		)
		(property "Description" ""
			(at 93.98 83.82 0)
			(effects
				(font
					(size 1.27 1.27)
				)
				(hide yes)
			)
		)
		(property "MPN" "ERJ2GE0R00X"
			(at 114.3 104.14 0)
			(effects
				(font
					(size 1.27 1.27)
					(thickness 0.15)
				)
				(justify left bottom)
				(hide yes)
			)
		)
		(property "Manufacturer" "Panasonic"
			(at 114.3 106.68 0)
			(effects
				(font
					(size 1.27 1.27)
					(thickness 0.15)
				)
				(justify left bottom)
				(hide yes)
			)
		)
		(property "License" "Apache-2.0"
			(at 114.3 109.22 0)
			(effects
				(font
					(size 1.27 1.27)
					(thickness 0.15)
				)
				(justify left bottom)
				(hide yes)
			)
		)
		(property "Author" "Antmicro"
			(at 114.3 111.76 0)
			(effects
				(font
					(size 1.27 1.27)
					(thickness 0.15)
				)
				(justify left bottom)
				(hide yes)
			)
		)
		(property "Val" "0R"
			(at 100.33 82.55 0)
			(effects
				(font
					(size 1.27 1.27)
					(thickness 0.15)
				)
			)
		)
		(property "Tolerance" "~"
			(at 114.3 93.98 0)
			(effects
				(font
					(size 1.27 1.27)
				)
				(justify left bottom)
				(hide yes)
			)
		)
		(property "Current" "1A"
			(at 114.3 114.3 0)
			(effects
				(font
					(size 1.27 1.27)
					(thickness 0.15)
				)
				(justify left bottom)
				(hide yes)
			)
		)
		(property "Public" "False"
			(at 114.3 114.3 0)
			(effects
				(font
					(size 1.27 1.27)
				)
				(justify left bottom)
				(hide yes)
			)
		)
		(pin "1"
		)
		(pin "2"
		)
		(instances
			(project "com-express-7-baseboard"
				(path ""
					(reference "R3")
					(unit 1)
				)
			)
		)
	)
	(symbol
		(lib_id "antmicroTVSDiodes:TPD2E2U06_SC70")
		(at 227.33 247.65 90)
		(mirror x)
		(unit 1)
		(exclude_from_sim no)
		(in_bom yes)
		(on_board yes)
		(dnp no)
		(fields_autoplaced yes)
		(property "Reference" "D3"
			(at 236.22 251.46 90)
			(effects
				(font
					(size 1.27 1.27)
					(thickness 0.15)
				)
				(justify right)
			)
		)
		(property "Value" "TPD2E2U06_SC70"
			(at 229.87 260.35 0)
			(effects
				(font
					(size 1.27 1.27)
					(thickness 0.15)
				)
				(justify left bottom)
				(hide yes)
			)
		)
		(property "Footprint" "antmicro-footprints:SC70-3"
			(at 232.41 260.35 0)
			(effects
				(font
					(size 1.27 1.27)
					(thickness 0.15)
				)
				(justify left bottom)
				(hide yes)
			)
		)
		(property "Datasheet" "https://www.ti.com/lit/ds/symlink/tpd2e2u06.pdf?ts=1706006131823&ref_url=https%253A%252F%252Fwww.ti.com%252Finterface%252Fdiodes%252Fesd-protection-diodes%252Fproducts.html"
			(at 234.95 260.35 0)
			(effects
				(font
					(size 1.27 1.27)
					(thickness 0.15)
				)
				(justify left bottom)
				(hide yes)
			)
		)
		(property "Description" ""
			(at 227.33 247.65 0)
			(effects
				(font
					(size 1.27 1.27)
				)
				(hide yes)
			)
		)
		(property "MPN" "TPD2E2U06DCKR"
			(at 236.22 254 90)
			(effects
				(font
					(size 1.27 1.27)
					(thickness 0.15)
				)
				(justify right)
			)
		)
		(property "Manufacturer" "Texas Instruments"
			(at 237.49 260.35 0)
			(effects
				(font
					(size 1.27 1.27)
					(thickness 0.15)
				)
				(justify left bottom)
				(hide yes)
			)
		)
		(property "Author" "Antmicro"
			(at 240.03 260.35 0)
			(effects
				(font
					(size 1.27 1.27)
					(thickness 0.15)
				)
				(justify left bottom)
				(hide yes)
			)
		)
		(property "License" "Apache-2.0"
			(at 242.57 260.35 0)
			(effects
				(font
					(size 1.27 1.27)
					(thickness 0.15)
				)
				(justify left bottom)
				(hide yes)
			)
		)
		(pin "2"
		)
		(pin "3"
		)
		(pin "1"
		)
		(instances
			(project "com-express-7-baseboard"
				(path ""
					(reference "D3")
					(unit 1)
				)
			)
		)
	)
	(symbol
		(lib_id "antmicropower:GND")
		(at 280.67 149.86 0)
		(unit 1)
		(exclude_from_sim no)
		(in_bom yes)
		(on_board yes)
		(dnp no)
		(property "Reference" "#PWR032"
			(at 280.67 156.21 0)
			(effects
				(font
					(size 1.27 1.27)
				)
				(justify left bottom)
				(hide yes)
			)
		)
		(property "Value" "GND"
			(at 280.67 153.67 0)
			(effects
				(font
					(size 1.27 1.27)
				)
			)
		)
		(property "Footprint" ""
			(at 280.67 149.86 0)
			(effects
				(font
					(size 1.27 1.27)
				)
				(justify left bottom)
				(hide yes)
			)
		)
		(property "Datasheet" ""
			(at 280.67 149.86 0)
			(effects
				(font
					(size 1.27 1.27)
				)
				(justify left bottom)
				(hide yes)
			)
		)
		(property "Description" ""
			(at 280.67 149.86 0)
			(effects
				(font
					(size 1.27 1.27)
				)
				(hide yes)
			)
		)
		(property "Author" "Antmicro"
			(at 289.56 157.48 0)
			(effects
				(font
					(size 1.27 1.27)
					(thickness 0.15)
				)
				(justify left bottom)
				(hide yes)
			)
		)
		(property "License" "Apache-2.0"
			(at 289.56 160.02 0)
			(effects
				(font
					(size 1.27 1.27)
					(thickness 0.15)
				)
				(justify left bottom)
				(hide yes)
			)
		)
		(pin "1"
		)
		(instances
			(project "com-express-7-baseboard"
				(path ""
					(reference "#PWR032")
					(unit 1)
				)
			)
		)
	)
	(symbol
		(lib_id "antmicropower:GND")
		(at 204.47 233.68 0)
		(unit 1)
		(exclude_from_sim no)
		(in_bom yes)
		(on_board yes)
		(dnp no)
		(property "Reference" "#PWR018"
			(at 204.47 240.03 0)
			(effects
				(font
					(size 1.27 1.27)
				)
				(justify left bottom)
				(hide yes)
			)
		)
		(property "Value" "GND"
			(at 204.47 237.49 0)
			(effects
				(font
					(size 1.27 1.27)
				)
			)
		)
		(property "Footprint" ""
			(at 204.47 233.68 0)
			(effects
				(font
					(size 1.27 1.27)
				)
				(hide yes)
			)
		)
		(property "Datasheet" ""
			(at 204.47 233.68 0)
			(effects
				(font
					(size 1.27 1.27)
				)
				(hide yes)
			)
		)
		(property "Description" ""
			(at 204.47 233.68 0)
			(effects
				(font
					(size 1.27 1.27)
				)
				(hide yes)
			)
		)
		(property "Author" "Antmicro"
			(at 213.36 241.3 0)
			(effects
				(font
					(size 1.27 1.27)
					(thickness 0.15)
				)
				(justify left bottom)
				(hide yes)
			)
		)
		(property "License" "Apache-2.0"
			(at 213.36 243.84 0)
			(effects
				(font
					(size 1.27 1.27)
					(thickness 0.15)
				)
				(justify left bottom)
				(hide yes)
			)
		)
		(pin "1"
		)
		(instances
			(project "com-express-7-baseboard"
				(path ""
					(reference "#PWR018")
					(unit 1)
				)
			)
		)
	)
	(symbol
		(lib_id "antmicroCapacitors0402:C_1u_0402")
		(at 149.86 232.41 270)
		(mirror x)
		(unit 1)
		(exclude_from_sim no)
		(in_bom yes)
		(on_board yes)
		(dnp no)
		(property "Reference" "C2"
			(at 147.32 228.5935 90)
			(effects
				(font
					(size 1.27 1.27)
					(thickness 0.15)
				)
				(justify right)
			)
		)
		(property "Value" "C_1u_0402"
			(at 139.7 212.09 0)
			(effects
				(font
					(size 1.27 1.27)
					(thickness 0.15)
				)
				(justify left bottom)
				(hide yes)
			)
		)
		(property "Footprint" "antmicro-footprints:C_0402_1005Metric"
			(at 137.16 212.09 0)
			(effects
				(font
					(size 1.27 1.27)
					(thickness 0.15)
				)
				(justify left bottom)
				(hide yes)
			)
		)
		(property "Datasheet" "https://product.tdk.com/en/search/capacitor/ceramic/mlcc/info?part_no=C1005X6S1A105K050BC"
			(at 134.62 212.09 0)
			(effects
				(font
					(size 1.27 1.27)
					(thickness 0.15)
				)
				(justify left bottom)
				(hide yes)
			)
		)
		(property "Description" ""
			(at 149.86 232.41 0)
			(effects
				(font
					(size 1.27 1.27)
				)
				(hide yes)
			)
		)
		(property "MPN" "C1005X6S1A105K050BC"
			(at 132.08 212.09 0)
			(effects
				(font
					(size 1.27 1.27)
					(thickness 0.15)
				)
				(justify left bottom)
				(hide yes)
			)
		)
		(property "Manufacturer" "TDK"
			(at 129.54 212.09 0)
			(effects
				(font
					(size 1.27 1.27)
					(thickness 0.15)
				)
				(justify left bottom)
				(hide yes)
			)
		)
		(property "License" "Apache-2.0"
			(at 127 212.09 0)
			(effects
				(font
					(size 1.27 1.27)
					(thickness 0.15)
				)
				(justify left bottom)
				(hide yes)
			)
		)
		(property "Author" "Antmicro"
			(at 124.46 212.09 0)
			(effects
				(font
					(size 1.27 1.27)
					(thickness 0.15)
				)
				(justify left bottom)
				(hide yes)
			)
		)
		(property "Val" "1u"
			(at 147.32 231.1335 90)
			(effects
				(font
					(size 1.27 1.27)
					(thickness 0.15)
				)
				(justify right)
			)
		)
		(property "Voltage" ""
			(at 121.92 212.09 0)
			(effects
				(font
					(size 1.27 1.27)
				)
				(justify left bottom)
				(hide yes)
			)
		)
		(property "Dielectric" ""
			(at 119.38 212.09 0)
			(effects
				(font
					(size 1.27 1.27)
				)
				(justify left bottom)
				(hide yes)
			)
		)
		(property "Public" "False"
			(at 116.84 212.09 0)
			(effects
				(font
					(size 1.27 1.27)
				)
				(justify left bottom)
				(hide yes)
			)
		)
		(pin "1"
		)
		(pin "2"
		)
		(instances
			(project "com-express-7-baseboard"
				(path ""
					(reference "C2")
					(unit 1)
				)
			)
		)
	)
	(symbol
		(lib_id "antmicroTVSDiodes:TPD2E2U06_SC70")
		(at 227.33 176.53 90)
		(mirror x)
		(unit 1)
		(exclude_from_sim no)
		(in_bom yes)
		(on_board yes)
		(dnp no)
		(fields_autoplaced yes)
		(property "Reference" "D25"
			(at 236.22 180.34 90)
			(effects
				(font
					(size 1.27 1.27)
					(thickness 0.15)
				)
				(justify right)
			)
		)
		(property "Value" "TPD2E2U06_SC70"
			(at 229.87 189.23 0)
			(effects
				(font
					(size 1.27 1.27)
					(thickness 0.15)
				)
				(justify left bottom)
				(hide yes)
			)
		)
		(property "Footprint" "antmicro-footprints:SC70-3"
			(at 232.41 189.23 0)
			(effects
				(font
					(size 1.27 1.27)
					(thickness 0.15)
				)
				(justify left bottom)
				(hide yes)
			)
		)
		(property "Datasheet" "https://www.ti.com/lit/ds/symlink/tpd2e2u06.pdf?ts=1706006131823&ref_url=https%253A%252F%252Fwww.ti.com%252Finterface%252Fdiodes%252Fesd-protection-diodes%252Fproducts.html"
			(at 234.95 189.23 0)
			(effects
				(font
					(size 1.27 1.27)
					(thickness 0.15)
				)
				(justify left bottom)
				(hide yes)
			)
		)
		(property "Description" ""
			(at 227.33 176.53 0)
			(effects
				(font
					(size 1.27 1.27)
				)
				(hide yes)
			)
		)
		(property "MPN" "TPD2E2U06DCKR"
			(at 236.22 182.88 90)
			(effects
				(font
					(size 1.27 1.27)
					(thickness 0.15)
				)
				(justify right)
			)
		)
		(property "Manufacturer" "Texas Instruments"
			(at 237.49 189.23 0)
			(effects
				(font
					(size 1.27 1.27)
					(thickness 0.15)
				)
				(justify left bottom)
				(hide yes)
			)
		)
		(property "Author" "Antmicro"
			(at 240.03 189.23 0)
			(effects
				(font
					(size 1.27 1.27)
					(thickness 0.15)
				)
				(justify left bottom)
				(hide yes)
			)
		)
		(property "License" "Apache-2.0"
			(at 242.57 189.23 0)
			(effects
				(font
					(size 1.27 1.27)
					(thickness 0.15)
				)
				(justify left bottom)
				(hide yes)
			)
		)
		(pin "2"
		)
		(pin "1"
		)
		(pin "3"
		)
		(instances
			(project "com-express-7-baseboard"
				(path ""
					(reference "D25")
					(unit 1)
				)
			)
		)
	)
	(symbol
		(lib_id "antmicroCapacitors0603:C_22u_16V_0603")
		(at 280.67 148.59 90)
		(unit 1)
		(exclude_from_sim no)
		(in_bom yes)
		(on_board yes)
		(dnp no)
		(fields_autoplaced yes)
		(property "Reference" "C19"
			(at 283.21 144.7735 90)
			(effects
				(font
					(size 1.27 1.27)
					(thickness 0.15)
				)
				(justify right)
			)
		)
		(property "Value" "C_22u_16V_0603"
			(at 290.83 128.27 0)
			(effects
				(font
					(size 1.27 1.27)
					(thickness 0.15)
				)
				(justify left bottom)
				(hide yes)
			)
		)
		(property "Footprint" "antmicro-footprints:C_0603_1608Metric"
			(at 293.37 128.27 0)
			(effects
				(font
					(size 1.27 1.27)
					(thickness 0.15)
				)
				(justify left bottom)
				(hide yes)
			)
		)
		(property "Datasheet" "https://product.samsungsem.com/mlcc/CL10A226MO7JZN.do"
			(at 295.91 128.27 0)
			(effects
				(font
					(size 1.27 1.27)
					(thickness 0.15)
				)
				(justify left bottom)
				(hide yes)
			)
		)
		(property "Description" ""
			(at 280.67 148.59 0)
			(effects
				(font
					(size 1.27 1.27)
				)
				(hide yes)
			)
		)
		(property "MPN" "CL10A226MO7JZNC"
			(at 298.45 128.27 0)
			(effects
				(font
					(size 1.27 1.27)
					(thickness 0.15)
				)
				(justify left bottom)
				(hide yes)
			)
		)
		(property "Manufacturer" "Samsung Electro-Mechanics"
			(at 300.99 128.27 0)
			(effects
				(font
					(size 1.27 1.27)
					(thickness 0.15)
				)
				(justify left bottom)
				(hide yes)
			)
		)
		(property "License" "Apache-2.0"
			(at 303.53 128.27 0)
			(effects
				(font
					(size 1.27 1.27)
					(thickness 0.15)
				)
				(justify left bottom)
				(hide yes)
			)
		)
		(property "Author" "Antmicro"
			(at 306.07 128.27 0)
			(effects
				(font
					(size 1.27 1.27)
					(thickness 0.15)
				)
				(justify left bottom)
				(hide yes)
			)
		)
		(property "Val" "22u"
			(at 283.21 147.3135 90)
			(effects
				(font
					(size 1.27 1.27)
					(thickness 0.15)
				)
				(justify right)
			)
		)
		(property "Voltage" "16V"
			(at 308.61 128.27 0)
			(effects
				(font
					(size 1.27 1.27)
				)
				(justify left bottom)
				(hide yes)
			)
		)
		(property "Dielectric" ""
			(at 311.15 128.27 0)
			(effects
				(font
					(size 1.27 1.27)
				)
				(justify left bottom)
				(hide yes)
			)
		)
		(property "Public" "False"
			(at 313.69 128.27 0)
			(effects
				(font
					(size 1.27 1.27)
				)
				(justify left bottom)
				(hide yes)
			)
		)
		(pin "2"
		)
		(pin "1"
		)
		(instances
			(project "com-express-7-baseboard"
				(path ""
					(reference "C19")
					(unit 1)
				)
			)
		)
	)
	(symbol
		(lib_id "antmicroCapacitors0402:C_1u_0402")
		(at 195.58 232.41 270)
		(mirror x)
		(unit 1)
		(exclude_from_sim no)
		(in_bom yes)
		(on_board yes)
		(dnp no)
		(fields_autoplaced yes)
		(property "Reference" "C9"
			(at 193.04 228.5935 90)
			(effects
				(font
					(size 1.27 1.27)
					(thickness 0.15)
				)
				(justify right)
			)
		)
		(property "Value" "C_1u_0402"
			(at 185.42 212.09 0)
			(effects
				(font
					(size 1.27 1.27)
					(thickness 0.15)
				)
				(justify left bottom)
				(hide yes)
			)
		)
		(property "Footprint" "antmicro-footprints:C_0402_1005Metric"
			(at 182.88 212.09 0)
			(effects
				(font
					(size 1.27 1.27)
					(thickness 0.15)
				)
				(justify left bottom)
				(hide yes)
			)
		)
		(property "Datasheet" "https://product.tdk.com/en/search/capacitor/ceramic/mlcc/info?part_no=C1005X6S1A105K050BC"
			(at 180.34 212.09 0)
			(effects
				(font
					(size 1.27 1.27)
					(thickness 0.15)
				)
				(justify left bottom)
				(hide yes)
			)
		)
		(property "Description" ""
			(at 195.58 232.41 0)
			(effects
				(font
					(size 1.27 1.27)
				)
				(hide yes)
			)
		)
		(property "MPN" "C1005X6S1A105K050BC"
			(at 177.8 212.09 0)
			(effects
				(font
					(size 1.27 1.27)
					(thickness 0.15)
				)
				(justify left bottom)
				(hide yes)
			)
		)
		(property "Manufacturer" "TDK"
			(at 175.26 212.09 0)
			(effects
				(font
					(size 1.27 1.27)
					(thickness 0.15)
				)
				(justify left bottom)
				(hide yes)
			)
		)
		(property "License" "Apache-2.0"
			(at 172.72 212.09 0)
			(effects
				(font
					(size 1.27 1.27)
					(thickness 0.15)
				)
				(justify left bottom)
				(hide yes)
			)
		)
		(property "Author" "Antmicro"
			(at 170.18 212.09 0)
			(effects
				(font
					(size 1.27 1.27)
					(thickness 0.15)
				)
				(justify left bottom)
				(hide yes)
			)
		)
		(property "Val" "1u"
			(at 193.04 231.1335 90)
			(effects
				(font
					(size 1.27 1.27)
					(thickness 0.15)
				)
				(justify right)
			)
		)
		(property "Voltage" ""
			(at 167.64 212.09 0)
			(effects
				(font
					(size 1.27 1.27)
				)
				(justify left bottom)
				(hide yes)
			)
		)
		(property "Dielectric" ""
			(at 165.1 212.09 0)
			(effects
				(font
					(size 1.27 1.27)
				)
				(justify left bottom)
				(hide yes)
			)
		)
		(property "Public" "False"
			(at 162.56 212.09 0)
			(effects
				(font
					(size 1.27 1.27)
				)
				(justify left bottom)
				(hide yes)
			)
		)
		(pin "1"
		)
		(pin "2"
		)
		(instances
			(project "com-express-7-baseboard"
				(path ""
					(reference "C9")
					(unit 1)
				)
			)
		)
	)
	(symbol
		(lib_id "antmicroResistors0402:R_0R_0402")
		(at 93.98 63.5 0)
		(unit 1)
		(exclude_from_sim no)
		(in_bom yes)
		(on_board yes)
		(dnp no)
		(property "Reference" "R1"
			(at 92.71 62.23 0)
			(effects
				(font
					(size 1.27 1.27)
					(thickness 0.15)
				)
			)
		)
		(property "Value" "R_0R_0402"
			(at 114.3 76.2 0)
			(effects
				(font
					(size 1.27 1.27)
					(thickness 0.15)
				)
				(justify left bottom)
				(hide yes)
			)
		)
		(property "Footprint" "antmicro-footprints:R_0402_1005Metric"
			(at 114.3 78.74 0)
			(effects
				(font
					(size 1.27 1.27)
					(thickness 0.15)
				)
				(justify left bottom)
				(hide yes)
			)
		)
		(property "Datasheet" "https://industrial.panasonic.com/cdbs/www-data/pdf/RDA0000/AOA0000C301.pdf"
			(at 114.3 81.28 0)
			(effects
				(font
					(size 1.27 1.27)
					(thickness 0.15)
				)
				(justify left bottom)
				(hide yes)
			)
		)
		(property "Description" ""
			(at 93.98 63.5 0)
			(effects
				(font
					(size 1.27 1.27)
				)
				(hide yes)
			)
		)
		(property "MPN" "ERJ2GE0R00X"
			(at 114.3 83.82 0)
			(effects
				(font
					(size 1.27 1.27)
					(thickness 0.15)
				)
				(justify left bottom)
				(hide yes)
			)
		)
		(property "Manufacturer" "Panasonic"
			(at 114.3 86.36 0)
			(effects
				(font
					(size 1.27 1.27)
					(thickness 0.15)
				)
				(justify left bottom)
				(hide yes)
			)
		)
		(property "License" "Apache-2.0"
			(at 114.3 88.9 0)
			(effects
				(font
					(size 1.27 1.27)
					(thickness 0.15)
				)
				(justify left bottom)
				(hide yes)
			)
		)
		(property "Author" "Antmicro"
			(at 114.3 91.44 0)
			(effects
				(font
					(size 1.27 1.27)
					(thickness 0.15)
				)
				(justify left bottom)
				(hide yes)
			)
		)
		(property "Val" "0R"
			(at 100.33 62.23 0)
			(effects
				(font
					(size 1.27 1.27)
					(thickness 0.15)
				)
			)
		)
		(property "Tolerance" "~"
			(at 114.3 73.66 0)
			(effects
				(font
					(size 1.27 1.27)
				)
				(justify left bottom)
				(hide yes)
			)
		)
		(property "Current" "1A"
			(at 114.3 93.98 0)
			(effects
				(font
					(size 1.27 1.27)
					(thickness 0.15)
				)
				(justify left bottom)
				(hide yes)
			)
		)
		(property "Public" "False"
			(at 114.3 93.98 0)
			(effects
				(font
					(size 1.27 1.27)
				)
				(justify left bottom)
				(hide yes)
			)
		)
		(pin "1"
		)
		(pin "2"
		)
		(instances
			(project "com-express-7-baseboard"
				(path ""
					(reference "R1")
					(unit 1)
				)
			)
		)
	)
	(symbol
		(lib_id "antmicroResistors0402:R_2k2_0402")
		(at 204.47 232.41 270)
		(mirror x)
		(unit 1)
		(exclude_from_sim no)
		(in_bom yes)
		(on_board yes)
		(dnp no)
		(property "Reference" "R13"
			(at 199.39 228.6 90)
			(effects
				(font
					(size 1.27 1.27)
				)
				(justify left)
			)
		)
		(property "Value" "R_2k2_0402"
			(at 191.77 212.09 0)
			(effects
				(font
					(size 1.27 1.27)
					(thickness 0.15)
				)
				(justify left bottom)
				(hide yes)
			)
		)
		(property "Footprint" "antmicro-footprints:R_0402_1005Metric"
			(at 189.23 212.09 0)
			(effects
				(font
					(size 1.27 1.27)
					(thickness 0.15)
				)
				(justify left bottom)
				(hide yes)
			)
		)
		(property "Datasheet" "https://www.bourns.com/docs/product-datasheets/cr.pdf"
			(at 186.69 212.09 0)
			(effects
				(font
					(size 1.27 1.27)
					(thickness 0.15)
				)
				(justify left bottom)
				(hide yes)
			)
		)
		(property "Description" ""
			(at 204.47 232.41 0)
			(effects
				(font
					(size 1.27 1.27)
				)
				(hide yes)
			)
		)
		(property "Manufacturer" "Bourns"
			(at 181.61 212.09 0)
			(effects
				(font
					(size 1.27 1.27)
					(thickness 0.15)
				)
				(justify left bottom)
				(hide yes)
			)
		)
		(property "MPN" "CR0402-FX-2201GLF"
			(at 184.15 212.09 0)
			(effects
				(font
					(size 1.27 1.27)
					(thickness 0.15)
				)
				(justify left bottom)
				(hide yes)
			)
		)
		(property "Val" "2k2"
			(at 199.39 231.14 90)
			(effects
				(font
					(size 1.27 1.27)
					(thickness 0.15)
				)
				(justify left)
			)
		)
		(property "License" "Apache-2.0"
			(at 179.07 212.09 0)
			(effects
				(font
					(size 1.27 1.27)
					(thickness 0.15)
				)
				(justify left bottom)
				(hide yes)
			)
		)
		(property "Author" "Antmicro"
			(at 176.53 212.09 0)
			(effects
				(font
					(size 1.27 1.27)
					(thickness 0.15)
				)
				(justify left bottom)
				(hide yes)
			)
		)
		(property "Tolerance" "1%"
			(at 194.31 212.09 0)
			(effects
				(font
					(size 1.27 1.27)
				)
				(justify left bottom)
				(hide yes)
			)
		)
		(property "Public" "False"
			(at 173.99 212.09 0)
			(effects
				(font
					(size 1.27 1.27)
				)
				(justify left bottom)
				(hide yes)
			)
		)
		(pin "1"
		)
		(pin "2"
		)
		(instances
			(project "com-express-7-baseboard"
				(path ""
					(reference "R13")
					(unit 1)
				)
			)
		)
	)
	(symbol
		(lib_id "antmicroCapacitors0402:C_100n_0402")
		(at 270.51 219.71 270)
		(mirror x)
		(unit 1)
		(exclude_from_sim no)
		(in_bom yes)
		(on_board yes)
		(dnp no)
		(fields_autoplaced yes)
		(property "Reference" "C17"
			(at 267.97 215.8935 90)
			(effects
				(font
					(size 1.27 1.27)
					(thickness 0.15)
				)
				(justify right)
			)
		)
		(property "Value" "C_100n_0402"
			(at 260.35 199.39 0)
			(effects
				(font
					(size 1.27 1.27)
					(thickness 0.15)
				)
				(justify left bottom)
				(hide yes)
			)
		)
		(property "Footprint" "antmicro-footprints:C_0402_1005Metric"
			(at 257.81 199.39 0)
			(effects
				(font
					(size 1.27 1.27)
					(thickness 0.15)
				)
				(justify left bottom)
				(hide yes)
			)
		)
		(property "Datasheet" "https://www.murata.com/products/productdetail?partno=GRM155R61H104KE14%23"
			(at 255.27 199.39 0)
			(effects
				(font
					(size 1.27 1.27)
					(thickness 0.15)
				)
				(justify left bottom)
				(hide yes)
			)
		)
		(property "Description" ""
			(at 270.51 219.71 0)
			(effects
				(font
					(size 1.27 1.27)
				)
				(hide yes)
			)
		)
		(property "MPN" "GRM155R61H104KE14D"
			(at 252.73 199.39 0)
			(effects
				(font
					(size 1.27 1.27)
					(thickness 0.15)
				)
				(justify left bottom)
				(hide yes)
			)
		)
		(property "Manufacturer" "Murata"
			(at 250.19 199.39 0)
			(effects
				(font
					(size 1.27 1.27)
					(thickness 0.15)
				)
				(justify left bottom)
				(hide yes)
			)
		)
		(property "License" "Apache-2.0"
			(at 247.65 199.39 0)
			(effects
				(font
					(size 1.27 1.27)
					(thickness 0.15)
				)
				(justify left bottom)
				(hide yes)
			)
		)
		(property "Author" "Antmicro"
			(at 245.11 199.39 0)
			(effects
				(font
					(size 1.27 1.27)
					(thickness 0.15)
				)
				(justify left bottom)
				(hide yes)
			)
		)
		(property "Val" "100n"
			(at 267.97 218.4335 90)
			(effects
				(font
					(size 1.27 1.27)
					(thickness 0.15)
				)
				(justify right)
			)
		)
		(property "Voltage" "50V"
			(at 242.57 199.39 0)
			(effects
				(font
					(size 1.27 1.27)
				)
				(justify left bottom)
				(hide yes)
			)
		)
		(property "Dielectric" "X5R"
			(at 240.03 199.39 0)
			(effects
				(font
					(size 1.27 1.27)
				)
				(justify left bottom)
				(hide yes)
			)
		)
		(property "Public" "False"
			(at 237.49 199.39 0)
			(effects
				(font
					(size 1.27 1.27)
				)
				(justify left bottom)
				(hide yes)
			)
		)
		(pin "1"
		)
		(pin "2"
		)
		(instances
			(project "com-express-7-baseboard"
				(path ""
					(reference "C17")
					(unit 1)
				)
			)
		)
	)
	(symbol
		(lib_id "antmicropower:+3V3")
		(at 241.3 148.59 0)
		(unit 1)
		(exclude_from_sim no)
		(in_bom yes)
		(on_board yes)
		(dnp no)
		(property "Reference" "#PWR023"
			(at 256.54 148.59 0)
			(effects
				(font
					(size 1.27 1.27)
					(thickness 0.15)
				)
				(justify left bottom)
				(hide yes)
			)
		)
		(property "Value" "+3V3"
			(at 241.3 144.78 0)
			(effects
				(font
					(size 1.27 1.27)
					(thickness 0.15)
				)
			)
		)
		(property "Footprint" ""
			(at 256.54 156.21 0)
			(effects
				(font
					(size 1.27 1.27)
					(thickness 0.15)
				)
				(justify left bottom)
				(hide yes)
			)
		)
		(property "Datasheet" ""
			(at 256.54 158.75 0)
			(effects
				(font
					(size 1.27 1.27)
					(thickness 0.15)
				)
				(justify left bottom)
				(hide yes)
			)
		)
		(property "Description" ""
			(at 241.3 148.59 0)
			(effects
				(font
					(size 1.27 1.27)
				)
				(hide yes)
			)
		)
		(property "Author" "Antmicro"
			(at 256.54 151.13 0)
			(effects
				(font
					(size 1.27 1.27)
					(thickness 0.15)
				)
				(justify left bottom)
				(hide yes)
			)
		)
		(property "License" "Apache-2.0"
			(at 256.54 153.67 0)
			(effects
				(font
					(size 1.27 1.27)
					(thickness 0.15)
				)
				(justify left bottom)
				(hide yes)
			)
		)
		(pin "1"
		)
		(instances
			(project "com-express-7-baseboard"
				(path ""
					(reference "#PWR023")
					(unit 1)
				)
			)
		)
	)
	(symbol
		(lib_id "antmicropower:GND")
		(at 160.02 233.68 0)
		(unit 1)
		(exclude_from_sim no)
		(in_bom yes)
		(on_board yes)
		(dnp no)
		(property "Reference" "#PWR08"
			(at 168.91 236.22 0)
			(effects
				(font
					(size 1.27 1.27)
					(thickness 0.15)
				)
				(justify left bottom)
				(hide yes)
			)
		)
		(property "Value" "GND"
			(at 160.02 237.49 0)
			(effects
				(font
					(size 1.27 1.27)
					(thickness 0.15)
				)
			)
		)
		(property "Footprint" ""
			(at 168.91 241.3 0)
			(effects
				(font
					(size 1.27 1.27)
					(thickness 0.15)
				)
				(justify left bottom)
				(hide yes)
			)
		)
		(property "Datasheet" ""
			(at 168.91 246.38 0)
			(effects
				(font
					(size 1.27 1.27)
					(thickness 0.15)
				)
				(justify left bottom)
				(hide yes)
			)
		)
		(property "Description" ""
			(at 160.02 233.68 0)
			(effects
				(font
					(size 1.27 1.27)
				)
				(hide yes)
			)
		)
		(property "Author" "Antmicro"
			(at 168.91 241.3 0)
			(effects
				(font
					(size 1.27 1.27)
					(thickness 0.15)
				)
				(justify left bottom)
				(hide yes)
			)
		)
		(property "License" "Apache-2.0"
			(at 168.91 243.84 0)
			(effects
				(font
					(size 1.27 1.27)
					(thickness 0.15)
				)
				(justify left bottom)
				(hide yes)
			)
		)
		(pin "1"
		)
		(instances
			(project "com-express-7-baseboard"
				(path ""
					(reference "#PWR08")
					(unit 1)
				)
			)
		)
	)
	(symbol
		(lib_id "antmicropower:+5V")
		(at 280.67 140.97 0)
		(mirror y)
		(unit 1)
		(exclude_from_sim no)
		(in_bom yes)
		(on_board yes)
		(dnp no)
		(property "Reference" "#PWR031"
			(at 265.43 143.51 0)
			(effects
				(font
					(size 1.27 1.27)
					(thickness 0.15)
				)
				(justify left bottom)
				(hide yes)
			)
		)
		(property "Value" "+5V"
			(at 280.67 137.16 0)
			(effects
				(font
					(size 1.27 1.27)
					(thickness 0.15)
				)
			)
		)
		(property "Footprint" ""
			(at 265.43 148.59 0)
			(effects
				(font
					(size 1.27 1.27)
					(thickness 0.15)
				)
				(justify left bottom)
				(hide yes)
			)
		)
		(property "Datasheet" ""
			(at 265.43 151.13 0)
			(effects
				(font
					(size 1.27 1.27)
					(thickness 0.15)
				)
				(justify left bottom)
				(hide yes)
			)
		)
		(property "Description" ""
			(at 280.67 140.97 0)
			(effects
				(font
					(size 1.27 1.27)
				)
				(hide yes)
			)
		)
		(property "Author" "Antmicro"
			(at 265.43 148.59 0)
			(effects
				(font
					(size 1.27 1.27)
					(thickness 0.15)
				)
				(justify left bottom)
				(hide yes)
			)
		)
		(property "License" "Apache-2.0"
			(at 265.43 151.13 0)
			(effects
				(font
					(size 1.27 1.27)
					(thickness 0.15)
				)
				(justify left bottom)
				(hide yes)
			)
		)
		(pin "1"
		)
		(instances
			(project "com-express-7-baseboard"
				(path ""
					(reference "#PWR031")
					(unit 1)
				)
			)
		)
	)
	(symbol
		(lib_id "antmicropower:GND")
		(at 280.67 106.68 0)
		(mirror y)
		(unit 1)
		(exclude_from_sim no)
		(in_bom yes)
		(on_board yes)
		(dnp no)
		(property "Reference" "#PWR030"
			(at 271.78 109.22 0)
			(effects
				(font
					(size 1.27 1.27)
					(thickness 0.15)
				)
				(justify left bottom)
				(hide yes)
			)
		)
		(property "Value" "GND"
			(at 280.67 110.49 0)
			(effects
				(font
					(size 1.27 1.27)
					(thickness 0.15)
				)
			)
		)
		(property "Footprint" ""
			(at 271.78 114.3 0)
			(effects
				(font
					(size 1.27 1.27)
					(thickness 0.15)
				)
				(justify left bottom)
				(hide yes)
			)
		)
		(property "Datasheet" ""
			(at 271.78 119.38 0)
			(effects
				(font
					(size 1.27 1.27)
					(thickness 0.15)
				)
				(justify left bottom)
				(hide yes)
			)
		)
		(property "Description" ""
			(at 280.67 106.68 0)
			(effects
				(font
					(size 1.27 1.27)
				)
				(hide yes)
			)
		)
		(property "Author" "Antmicro"
			(at 271.78 114.3 0)
			(effects
				(font
					(size 1.27 1.27)
					(thickness 0.15)
				)
				(justify left bottom)
				(hide yes)
			)
		)
		(property "License" "Apache-2.0"
			(at 271.78 116.84 0)
			(effects
				(font
					(size 1.27 1.27)
					(thickness 0.15)
				)
				(justify left bottom)
				(hide yes)
			)
		)
		(pin "1"
		)
		(instances
			(project "com-express-7-baseboard"
				(path ""
					(reference "#PWR030")
					(unit 1)
				)
			)
		)
	)
	(symbol
		(lib_id "antmicroCapacitors0402:C_100n_0402")
		(at 274.32 100.33 270)
		(unit 1)
		(exclude_from_sim no)
		(in_bom yes)
		(on_board yes)
		(dnp no)
		(property "Reference" "C15"
			(at 274.955 100.965 90)
			(effects
				(font
					(size 1.27 1.27)
					(thickness 0.15)
				)
				(justify left)
			)
		)
		(property "Value" "C_100n_0402"
			(at 264.16 120.65 0)
			(effects
				(font
					(size 1.27 1.27)
					(thickness 0.15)
				)
				(justify left bottom)
				(hide yes)
			)
		)
		(property "Footprint" "antmicro-footprints:C_0402_1005Metric"
			(at 261.62 120.65 0)
			(effects
				(font
					(size 1.27 1.27)
					(thickness 0.15)
				)
				(justify left bottom)
				(hide yes)
			)
		)
		(property "Datasheet" "https://www.murata.com/products/productdetail?partno=GRM155R61H104KE14%23"
			(at 259.08 120.65 0)
			(effects
				(font
					(size 1.27 1.27)
					(thickness 0.15)
				)
				(justify left bottom)
				(hide yes)
			)
		)
		(property "Description" ""
			(at 274.32 100.33 0)
			(effects
				(font
					(size 1.27 1.27)
				)
				(hide yes)
			)
		)
		(property "MPN" "GRM155R61H104KE14D"
			(at 256.54 120.65 0)
			(effects
				(font
					(size 1.27 1.27)
					(thickness 0.15)
				)
				(justify left bottom)
				(hide yes)
			)
		)
		(property "Manufacturer" "Murata"
			(at 254 120.65 0)
			(effects
				(font
					(size 1.27 1.27)
					(thickness 0.15)
				)
				(justify left bottom)
				(hide yes)
			)
		)
		(property "License" "Apache-2.0"
			(at 251.46 120.65 0)
			(effects
				(font
					(size 1.27 1.27)
					(thickness 0.15)
				)
				(justify left bottom)
				(hide yes)
			)
		)
		(property "Author" "Antmicro"
			(at 248.92 120.65 0)
			(effects
				(font
					(size 1.27 1.27)
					(thickness 0.15)
				)
				(justify left bottom)
				(hide yes)
			)
		)
		(property "Val" "100n"
			(at 274.955 104.775 90)
			(effects
				(font
					(size 1.27 1.27)
					(thickness 0.15)
				)
				(justify left)
			)
		)
		(property "Voltage" "50V"
			(at 246.38 120.65 0)
			(effects
				(font
					(size 1.27 1.27)
				)
				(justify left bottom)
				(hide yes)
			)
		)
		(property "Dielectric" "X5R"
			(at 243.84 120.65 0)
			(effects
				(font
					(size 1.27 1.27)
				)
				(justify left bottom)
				(hide yes)
			)
		)
		(property "Public" "False"
			(at 241.3 120.65 0)
			(effects
				(font
					(size 1.27 1.27)
				)
				(justify left bottom)
				(hide yes)
			)
		)
		(pin "2"
		)
		(pin "1"
		)
		(instances
			(project "com-express-7-baseboard"
				(path ""
					(reference "C15")
					(unit 1)
				)
			)
		)
	)
	(symbol
		(lib_id "antmicroInterfaceDriversReceiversTransceivers:Trans_SM453229-381N7Y")
		(at 245.11 66.04 0)
		(unit 1)
		(exclude_from_sim no)
		(in_bom yes)
		(on_board yes)
		(dnp no)
		(fields_autoplaced yes)
		(property "Reference" "T6"
			(at 250.19 60.96 0)
			(effects
				(font
					(size 1.27 1.27)
					(thickness 0.15)
				)
			)
		)
		(property "Value" "Trans_SM453229-381N7Y"
			(at 271.78 78.74 0)
			(effects
				(font
					(size 1.27 1.27)
					(thickness 0.15)
				)
				(justify left bottom)
				(hide yes)
			)
		)
		(property "Footprint" "antmicro-footprints:Trans_Eth_4.7x3.3mm"
			(at 271.78 81.28 0)
			(effects
				(font
					(size 1.27 1.27)
					(thickness 0.15)
				)
				(justify left bottom)
				(hide yes)
			)
		)
		(property "Datasheet" "https://eu.mouser.com/datasheet/2/54/bourns_02132019_SM453229-381N7Y_datasheet-1532071.pdf"
			(at 271.78 83.82 0)
			(effects
				(font
					(size 1.27 1.27)
					(thickness 0.15)
				)
				(justify left bottom)
				(hide yes)
			)
		)
		(property "Description" ""
			(at 245.11 66.04 0)
			(effects
				(font
					(size 1.27 1.27)
				)
				(hide yes)
			)
		)
		(property "MPN" "SM453229-381N7Y"
			(at 250.19 63.5 0)
			(effects
				(font
					(size 1.27 1.27)
					(thickness 0.15)
				)
			)
		)
		(property "Manufacturer" "Bourns"
			(at 271.78 76.2 0)
			(effects
				(font
					(size 1.27 1.27)
					(thickness 0.15)
				)
				(justify left bottom)
				(hide yes)
			)
		)
		(property "Author" "Antmicro"
			(at 271.78 86.36 0)
			(effects
				(font
					(size 1.27 1.27)
					(thickness 0.15)
				)
				(justify left bottom)
				(hide yes)
			)
		)
		(property "License" "Apache-2.0"
			(at 271.78 88.9 0)
			(effects
				(font
					(size 1.27 1.27)
					(thickness 0.15)
				)
				(justify left bottom)
				(hide yes)
			)
		)
		(pin "7"
		)
		(pin "3"
		)
		(pin "1"
		)
		(pin "5"
		)
		(pin "2"
		)
		(pin "6"
		)
		(instances
			(project "com-express-7-baseboard"
				(path ""
					(reference "T6")
					(unit 1)
				)
			)
		)
	)
	(symbol
		(lib_id "antmicroResistors0402:R_10k_0402")
		(at 241.3 156.21 270)
		(mirror x)
		(unit 1)
		(exclude_from_sim no)
		(in_bom yes)
		(on_board yes)
		(dnp no)
		(property "Reference" "R24"
			(at 240.03 152.4 90)
			(effects
				(font
					(size 1.27 1.27)
					(thickness 0.15)
				)
				(justify right)
			)
		)
		(property "Value" "R_10k_0402"
			(at 228.6 135.89 0)
			(effects
				(font
					(size 1.27 1.27)
					(thickness 0.15)
				)
				(justify left bottom)
				(hide yes)
			)
		)
		(property "Footprint" "antmicro-footprints:R_0402_1005Metric"
			(at 226.06 135.89 0)
			(effects
				(font
					(size 1.27 1.27)
					(thickness 0.15)
				)
				(justify left bottom)
				(hide yes)
			)
		)
		(property "Datasheet" "https://www.bourns.com/docs/product-datasheets/cr.pdf"
			(at 223.52 135.89 0)
			(effects
				(font
					(size 1.27 1.27)
					(thickness 0.15)
				)
				(justify left bottom)
				(hide yes)
			)
		)
		(property "Description" ""
			(at 241.3 156.21 0)
			(effects
				(font
					(size 1.27 1.27)
				)
				(hide yes)
			)
		)
		(property "MPN" "CR0402-FX-1002GLF"
			(at 220.98 135.89 0)
			(effects
				(font
					(size 1.27 1.27)
					(thickness 0.15)
				)
				(justify left bottom)
				(hide yes)
			)
		)
		(property "Manufacturer" "Bourns"
			(at 218.44 135.89 0)
			(effects
				(font
					(size 1.27 1.27)
					(thickness 0.15)
				)
				(justify left bottom)
				(hide yes)
			)
		)
		(property "License" "Apache-2.0"
			(at 215.9 135.89 0)
			(effects
				(font
					(size 1.27 1.27)
					(thickness 0.15)
				)
				(justify left bottom)
				(hide yes)
			)
		)
		(property "Author" "Antmicro"
			(at 213.36 135.89 0)
			(effects
				(font
					(size 1.27 1.27)
					(thickness 0.15)
				)
				(justify left bottom)
				(hide yes)
			)
		)
		(property "Val" "10k"
			(at 240.03 154.94 90)
			(effects
				(font
					(size 1.27 1.27)
					(thickness 0.15)
				)
				(justify right)
			)
		)
		(property "Tolerance" "1%"
			(at 231.14 135.89 0)
			(effects
				(font
					(size 1.27 1.27)
				)
				(justify left bottom)
				(hide yes)
			)
		)
		(property "Public" "False"
			(at 210.82 135.89 0)
			(effects
				(font
					(size 1.27 1.27)
				)
				(justify left bottom)
				(hide yes)
			)
		)
		(pin "1"
		)
		(pin "2"
		)
		(instances
			(project "com-express-7-baseboard"
				(path ""
					(reference "R24")
					(unit 1)
				)
			)
		)
	)
	(symbol
		(lib_id "antmicropower:GND")
		(at 270.51 219.71 0)
		(mirror y)
		(unit 1)
		(exclude_from_sim no)
		(in_bom yes)
		(on_board yes)
		(dnp no)
		(property "Reference" "#PWR029"
			(at 261.62 222.25 0)
			(effects
				(font
					(size 1.27 1.27)
					(thickness 0.15)
				)
				(justify left bottom)
				(hide yes)
			)
		)
		(property "Value" "GND"
			(at 270.51 223.52 0)
			(effects
				(font
					(size 1.27 1.27)
					(thickness 0.15)
				)
			)
		)
		(property "Footprint" ""
			(at 261.62 227.33 0)
			(effects
				(font
					(size 1.27 1.27)
					(thickness 0.15)
				)
				(justify left bottom)
				(hide yes)
			)
		)
		(property "Datasheet" ""
			(at 261.62 232.41 0)
			(effects
				(font
					(size 1.27 1.27)
					(thickness 0.15)
				)
				(justify left bottom)
				(hide yes)
			)
		)
		(property "Description" ""
			(at 270.51 219.71 0)
			(effects
				(font
					(size 1.27 1.27)
				)
				(hide yes)
			)
		)
		(property "Author" "Antmicro"
			(at 261.62 227.33 0)
			(effects
				(font
					(size 1.27 1.27)
					(thickness 0.15)
				)
				(justify left bottom)
				(hide yes)
			)
		)
		(property "License" "Apache-2.0"
			(at 261.62 229.87 0)
			(effects
				(font
					(size 1.27 1.27)
					(thickness 0.15)
				)
				(justify left bottom)
				(hide yes)
			)
		)
		(pin "1"
		)
		(instances
			(project "com-express-7-baseboard"
				(path ""
					(reference "#PWR029")
					(unit 1)
				)
			)
		)
	)
	(symbol
		(lib_id "antmicroResistors0402:R_75R_0402")
		(at 237.49 68.58 0)
		(unit 1)
		(exclude_from_sim no)
		(in_bom yes)
		(on_board yes)
		(dnp no)
		(property "Reference" "R15"
			(at 236.22 67.31 0)
			(effects
				(font
					(size 1.27 1.27)
					(thickness 0.15)
				)
			)
		)
		(property "Value" "R_75R_0402"
			(at 257.81 81.28 0)
			(effects
				(font
					(size 1.27 1.27)
					(thickness 0.15)
				)
				(justify left bottom)
				(hide yes)
			)
		)
		(property "Footprint" "antmicro-footprints:R_0402_1005Metric"
			(at 257.81 83.82 0)
			(effects
				(font
					(size 1.27 1.27)
					(thickness 0.15)
				)
				(justify left bottom)
				(hide yes)
			)
		)
		(property "Datasheet" "https://www.bourns.com/docs/product-datasheets/cr.pdf"
			(at 257.81 86.36 0)
			(effects
				(font
					(size 1.27 1.27)
					(thickness 0.15)
				)
				(justify left bottom)
				(hide yes)
			)
		)
		(property "Description" ""
			(at 237.49 68.58 0)
			(effects
				(font
					(size 1.27 1.27)
				)
				(hide yes)
			)
		)
		(property "MPN" "CR0402-FX-75R0GLF"
			(at 257.81 88.9 0)
			(effects
				(font
					(size 1.27 1.27)
					(thickness 0.15)
				)
				(justify left bottom)
				(hide yes)
			)
		)
		(property "Manufacturer" "Bourns"
			(at 257.81 91.44 0)
			(effects
				(font
					(size 1.27 1.27)
					(thickness 0.15)
				)
				(justify left bottom)
				(hide yes)
			)
		)
		(property "License" "Apache-2.0"
			(at 257.81 93.98 0)
			(effects
				(font
					(size 1.27 1.27)
					(thickness 0.15)
				)
				(justify left bottom)
				(hide yes)
			)
		)
		(property "Author" "Antmicro"
			(at 257.81 96.52 0)
			(effects
				(font
					(size 1.27 1.27)
					(thickness 0.15)
				)
				(justify left bottom)
				(hide yes)
			)
		)
		(property "Val" "75R"
			(at 243.84 67.31 0)
			(effects
				(font
					(size 1.27 1.27)
					(thickness 0.15)
				)
			)
		)
		(property "Tolerance" "1%"
			(at 257.81 78.74 0)
			(effects
				(font
					(size 1.27 1.27)
				)
				(justify left bottom)
				(hide yes)
			)
		)
		(property "Public" "False"
			(at 257.81 99.06 0)
			(effects
				(font
					(size 1.27 1.27)
				)
				(justify left bottom)
				(hide yes)
			)
		)
		(pin "2"
		)
		(pin "1"
		)
		(instances
			(project "com-express-7-baseboard"
				(path ""
					(reference "R15")
					(unit 1)
				)
			)
		)
	)
	(symbol
		(lib_id "antmicroResistors0402:R_0R_0402")
		(at 238.76 171.45 0)
		(mirror y)
		(unit 1)
		(exclude_from_sim no)
		(in_bom yes)
		(on_board yes)
		(dnp no)
		(property "Reference" "R20"
			(at 232.41 170.18 0)
			(effects
				(font
					(size 1.27 1.27)
					(thickness 0.15)
				)
			)
		)
		(property "Value" "R_0R_0402"
			(at 218.44 184.15 0)
			(effects
				(font
					(size 1.27 1.27)
					(thickness 0.15)
				)
				(justify left bottom)
				(hide yes)
			)
		)
		(property "Footprint" "antmicro-footprints:R_0402_1005Metric"
			(at 218.44 186.69 0)
			(effects
				(font
					(size 1.27 1.27)
					(thickness 0.15)
				)
				(justify left bottom)
				(hide yes)
			)
		)
		(property "Datasheet" "https://industrial.panasonic.com/cdbs/www-data/pdf/RDA0000/AOA0000C301.pdf"
			(at 218.44 189.23 0)
			(effects
				(font
					(size 1.27 1.27)
					(thickness 0.15)
				)
				(justify left bottom)
				(hide yes)
			)
		)
		(property "Description" ""
			(at 238.76 171.45 0)
			(effects
				(font
					(size 1.27 1.27)
				)
				(hide yes)
			)
		)
		(property "MPN" "ERJ2GE0R00X"
			(at 218.44 191.77 0)
			(effects
				(font
					(size 1.27 1.27)
					(thickness 0.15)
				)
				(justify left bottom)
				(hide yes)
			)
		)
		(property "Manufacturer" "Panasonic"
			(at 218.44 194.31 0)
			(effects
				(font
					(size 1.27 1.27)
					(thickness 0.15)
				)
				(justify left bottom)
				(hide yes)
			)
		)
		(property "License" "Apache-2.0"
			(at 218.44 196.85 0)
			(effects
				(font
					(size 1.27 1.27)
					(thickness 0.15)
				)
				(justify left bottom)
				(hide yes)
			)
		)
		(property "Author" "Antmicro"
			(at 218.44 199.39 0)
			(effects
				(font
					(size 1.27 1.27)
					(thickness 0.15)
				)
				(justify left bottom)
				(hide yes)
			)
		)
		(property "Val" "0R"
			(at 240.03 170.18 0)
			(effects
				(font
					(size 1.27 1.27)
					(thickness 0.15)
				)
			)
		)
		(property "Tolerance" "~"
			(at 218.44 181.61 0)
			(effects
				(font
					(size 1.27 1.27)
				)
				(justify left bottom)
				(hide yes)
			)
		)
		(property "Current" "1A"
			(at 218.44 201.93 0)
			(effects
				(font
					(size 1.27 1.27)
					(thickness 0.15)
				)
				(justify left bottom)
				(hide yes)
			)
		)
		(property "Public" "False"
			(at 218.44 201.93 0)
			(effects
				(font
					(size 1.27 1.27)
				)
				(justify left bottom)
				(hide yes)
			)
		)
		(pin "1"
		)
		(pin "2"
		)
		(instances
			(project "com-express-7-baseboard"
				(path ""
					(reference "R20")
					(unit 1)
				)
			)
		)
	)
	(symbol
		(lib_name "Amphenol_RJE361882415_1")
		(lib_id "antmicroModularConnectorsJacks:Amphenol_RJE361882415")
		(at 135.89 167.64 0)
		(mirror y)
		(unit 2)
		(exclude_from_sim no)
		(in_bom yes)
		(on_board yes)
		(dnp no)
		(fields_autoplaced yes)
		(property "Reference" "J1"
			(at 123.825 160.02 0)
			(effects
				(font
					(size 1.27 1.27)
				)
			)
		)
		(property "Value" "Amphenol_RJE361882415"
			(at 123.825 162.56 0)
			(effects
				(font
					(size 1.27 1.27)
				)
				(hide yes)
			)
		)
		(property "Footprint" "antmicro-footprints:RJ45_RJE361882415"
			(at 96.52 180.34 0)
			(effects
				(font
					(size 1.27 1.27)
					(thickness 0.15)
				)
				(justify left bottom)
				(hide yes)
			)
		)
		(property "Datasheet" "https://cdn.amphenol-cs.com/media/wysiwyg/files/drawing/p-rje36-188-2xx5.pdf"
			(at 96.52 182.88 0)
			(effects
				(font
					(size 1.27 1.27)
					(thickness 0.15)
				)
				(justify left bottom)
				(hide yes)
			)
		)
		(property "Description" ""
			(at 135.89 167.64 0)
			(effects
				(font
					(size 1.27 1.27)
				)
				(hide yes)
			)
		)
		(property "MPN" "RJE361882415"
			(at 123.825 162.56 0)
			(effects
				(font
					(size 1.27 1.27)
					(thickness 0.15)
				)
			)
		)
		(property "Manufacturer" "Amphenol"
			(at 96.52 185.42 0)
			(effects
				(font
					(size 1.27 1.27)
					(thickness 0.15)
				)
				(justify left bottom)
				(hide yes)
			)
		)
		(property "Author" "Antmicro"
			(at 96.52 187.96 0)
			(effects
				(font
					(size 1.27 1.27)
					(thickness 0.15)
				)
				(justify left bottom)
				(hide yes)
			)
		)
		(property "License" "Apache-2.0"
			(at 96.52 190.5 0)
			(effects
				(font
					(size 1.27 1.27)
					(thickness 0.15)
				)
				(justify left bottom)
				(hide yes)
			)
		)
		(pin "U2"
		)
		(pin "1"
		)
		(pin "U10"
		)
		(pin "U5"
		)
		(pin "U4"
		)
		(pin "U17"
		)
		(pin "U7"
		)
		(pin "U14"
		)
		(pin "U6"
		)
		(pin "U12"
		)
		(pin "U13"
		)
		(pin "D4"
		)
		(pin "U18"
		)
		(pin "U1"
		)
		(pin "8"
		)
		(pin "MP"
		)
		(pin "U15"
		)
		(pin "6"
		)
		(pin "U16"
		)
		(pin "U9"
		)
		(pin "D2"
		)
		(pin "3"
		)
		(pin "2"
		)
		(pin "D3"
		)
		(pin "7"
		)
		(pin "4"
		)
		(pin "U11"
		)
		(pin "5"
		)
		(pin "D1"
		)
		(pin "U3"
		)
		(pin "U8"
		)
		(instances
			(project "com-express-7-baseboard"
				(path ""
					(reference "J1")
					(unit 2)
				)
			)
		)
	)
	(symbol
		(lib_name "Amphenol_RJE361882415_2")
		(lib_id "antmicroModularConnectorsJacks:Amphenol_RJE361882415")
		(at 135.89 237.49 0)
		(mirror y)
		(unit 3)
		(exclude_from_sim no)
		(in_bom yes)
		(on_board yes)
		(dnp no)
		(fields_autoplaced yes)
		(property "Reference" "J1"
			(at 123.825 229.87 0)
			(effects
				(font
					(size 1.27 1.27)
				)
			)
		)
		(property "Value" "Amphenol_RJE361882415"
			(at 123.825 232.41 0)
			(effects
				(font
					(size 1.27 1.27)
				)
				(hide yes)
			)
		)
		(property "Footprint" "antmicro-footprints:RJ45_RJE361882415"
			(at 96.52 250.19 0)
			(effects
				(font
					(size 1.27 1.27)
					(thickness 0.15)
				)
				(justify left bottom)
				(hide yes)
			)
		)
		(property "Datasheet" "https://cdn.amphenol-cs.com/media/wysiwyg/files/drawing/p-rje36-188-2xx5.pdf"
			(at 96.52 252.73 0)
			(effects
				(font
					(size 1.27 1.27)
					(thickness 0.15)
				)
				(justify left bottom)
				(hide yes)
			)
		)
		(property "Description" "Modular Connectors / Ethernet Connectors MODULAR JACK"
			(at 135.89 237.49 0)
			(effects
				(font
					(size 1.27 1.27)
				)
				(hide yes)
			)
		)
		(property "MPN" "RJE361882415"
			(at 123.825 232.41 0)
			(effects
				(font
					(size 1.27 1.27)
					(thickness 0.15)
				)
			)
		)
		(property "Manufacturer" "Amphenol"
			(at 96.52 255.27 0)
			(effects
				(font
					(size 1.27 1.27)
					(thickness 0.15)
				)
				(justify left bottom)
				(hide yes)
			)
		)
		(property "Author" "Antmicro"
			(at 96.52 257.81 0)
			(effects
				(font
					(size 1.27 1.27)
					(thickness 0.15)
				)
				(justify left bottom)
				(hide yes)
			)
		)
		(property "License" "Apache-2.0"
			(at 96.52 260.35 0)
			(effects
				(font
					(size 1.27 1.27)
					(thickness 0.15)
				)
				(justify left bottom)
				(hide yes)
			)
		)
		(pin "U2"
		)
		(pin "1"
		)
		(pin "U10"
		)
		(pin "U5"
		)
		(pin "U4"
		)
		(pin "U17"
		)
		(pin "U7"
		)
		(pin "U14"
		)
		(pin "U6"
		)
		(pin "U12"
		)
		(pin "U13"
		)
		(pin "D4"
		)
		(pin "U18"
		)
		(pin "U1"
		)
		(pin "8"
		)
		(pin "MP"
		)
		(pin "U15"
		)
		(pin "6"
		)
		(pin "U16"
		)
		(pin "U9"
		)
		(pin "D2"
		)
		(pin "3"
		)
		(pin "2"
		)
		(pin "D3"
		)
		(pin "7"
		)
		(pin "4"
		)
		(pin "U11"
		)
		(pin "5"
		)
		(pin "D1"
		)
		(pin "U3"
		)
		(pin "U8"
		)
		(instances
			(project "com-express-7-baseboard"
				(path ""
					(reference "J1")
					(unit 3)
				)
			)
		)
	)
	(symbol
		(lib_id "antmicroCapacitorspol:C_Pol_100u_10V_KEMET-T520-B")
		(at 160.02 157.48 270)
		(unit 1)
		(exclude_from_sim no)
		(in_bom yes)
		(on_board yes)
		(dnp no)
		(fields_autoplaced yes)
		(property "Reference" "C3"
			(at 162.56 156.9465 90)
			(effects
				(font
					(size 1.27 1.27)
					(thickness 0.15)
				)
				(justify left)
			)
		)
		(property "Value" "C_Pol_100u_10V_KEMET-T520-B"
			(at 157.48 171.45 0)
			(effects
				(font
					(size 1.27 1.27)
					(thickness 0.15)
				)
				(justify left bottom)
				(hide yes)
			)
		)
		(property "Footprint" "antmicro-footprints:C_Pol_EIA-B"
			(at 152.4 171.45 0)
			(effects
				(font
					(size 1.27 1.27)
					(thickness 0.15)
				)
				(justify left bottom)
				(hide yes)
			)
		)
		(property "Datasheet" "https://www.kemet.com/en/us/capacitors/product/T520B107M010ATE070.html"
			(at 149.86 171.45 0)
			(effects
				(font
					(size 1.27 1.27)
					(thickness 0.15)
				)
				(justify left bottom)
				(hide yes)
			)
		)
		(property "Description" ""
			(at 160.02 157.48 0)
			(effects
				(font
					(size 1.27 1.27)
				)
				(hide yes)
			)
		)
		(property "Val" "100u"
			(at 162.56 159.4865 90)
			(effects
				(font
					(size 1.27 1.27)
					(thickness 0.15)
				)
				(justify left)
			)
		)
		(property "MPN" "T520B107M010ATE070"
			(at 147.32 171.45 0)
			(effects
				(font
					(size 1.27 1.27)
					(thickness 0.15)
				)
				(justify left bottom)
				(hide yes)
			)
		)
		(property "Manufacturer" "KEMET"
			(at 144.78 171.45 0)
			(effects
				(font
					(size 1.27 1.27)
					(thickness 0.15)
				)
				(justify left bottom)
				(hide yes)
			)
		)
		(property "License" "Apache-2.0"
			(at 142.24 171.45 0)
			(effects
				(font
					(size 1.27 1.27)
					(thickness 0.15)
				)
				(justify left bottom)
				(hide yes)
			)
		)
		(property "Author" "Antmicro"
			(at 139.7 171.45 0)
			(effects
				(font
					(size 1.27 1.27)
					(thickness 0.15)
				)
				(justify left bottom)
				(hide yes)
			)
		)
		(property "Voltage" "10V"
			(at 162.56 162.0265 90)
			(effects
				(font
					(size 1.27 1.27)
				)
				(justify left)
			)
		)
		(property "Dielectric" "template_dielectric"
			(at 134.62 171.45 0)
			(effects
				(font
					(size 1.27 1.27)
				)
				(justify left bottom)
				(hide yes)
			)
		)
		(property "Public" "False"
			(at 132.08 171.45 0)
			(effects
				(font
					(size 1.27 1.27)
				)
				(justify left bottom)
				(hide yes)
			)
		)
		(pin "1"
		)
		(pin "2"
		)
		(instances
			(project "com-express-7-baseboard"
				(path ""
					(reference "C3")
					(unit 1)
				)
			)
		)
	)
)
